FILE_TYPE = MACRO_DRAWING;
SET COLOR_WIRE YELLOW;
SET COLOR_PROP MONO;
SET COLOR_DOT WHITE;
SET COLOR_ARC YELLOW;
SET COLOR_BODY GREEN;
SET COLOR_NOTE MONO;
SET PROP_DISPLAY VALUE;
SET PAGE_NUMBER P96;
FORCEADD PVCCIO_CPU0..1
(1800 4700);
FORCEPROP 3 LASTPIN (1800 4650) SIG_NAME PVCCIO_CPU0\g
J 0
(1810 4660);
DISPLAY 0.659574 (1810 4660);
PAINT MONO (1810 4660);
DISPLAY INVISIBLE (1810 4660);
FORCEPROP 1 LAST VOLTAGE 1.1V
J 0
(1755 4657);
DISPLAY 0.340426 (1755 4657);
PAINT SKYBLUE (1755 4657);
DISPLAY INVISIBLE (1755 4657);
FORCEPROP 2 LAST CDS_LIB mstr_symbols
J 0
(1800 4700);
PAINT ORANGE (1800 4700);
DISPLAY INVISIBLE (1800 4700);
FORCEPROP 1 LAST BODY_TYPE PLUMBING
J 0
(1755 4657);
DISPLAY 0.340426 (1755 4657);
PAINT GREEN (1755 4657);
DISPLAY INVISIBLE (1755 4657);
FORCEPROP 1 LAST PATH I1
J 0
(1850 4725);
DISPLAY 0.872340 (1850 4725);
PAINT AQUA (1850 4725);
DISPLAY INVISIBLE (1850 4725);
FORCEPROP 1 LAST HDL_POWER PVCCIO_CPU0
J 1
(1800 4750);
DISPLAY 0.872340 (1800 4750);
PAINT GREEN (1800 4750);
DISPLAY INVISIBLE (1800 4750);
FORCEADD OFFPAGE..2
(3375 3650);
FORCEPROP 2 LAST $XR0 21 
J 0
(3564 3650);
DISPLAY 0.638298 (3564 3650);
PAINT MONO (3564 3650);
FORCEPROP 2 LAST CDS_LIB mstr_standard
J 0
(3375 3650);
PAINT ORANGE (3375 3650);
DISPLAY INVISIBLE (3375 3650);
FORCEPROP 1 LAST OFFPAGE TRUE
J 0
(3700 3525);
DISPLAY 1.404255 (3700 3525);
PAINT GREEN (3700 3525);
DISPLAY INVISIBLE (3700 3525);
FORCEPROP 1 LAST COMMENT_BODY TRUE
J 0
(3330 3555);
DISPLAY 1.404255 (3330 3555);
PAINT PEACH (3330 3555);
DISPLAY INVISIBLE (3330 3555);
FORCEPROP 2 LAST PATH I10
J 0
(3575 3700);
DISPLAY 1.021277 (3575 3700);
PAINT ORANGE (3575 3700);
DISPLAY INVISIBLE (3575 3700);
FORCEADD OFFPAGE..2
(3375 3350);
FORCEPROP 2 LAST $XR0 21 
J 0
(3564 3350);
DISPLAY 0.638298 (3564 3350);
PAINT MONO (3564 3350);
FORCEPROP 2 LAST CDS_LIB mstr_standard
J 0
(3375 3350);
PAINT ORANGE (3375 3350);
DISPLAY INVISIBLE (3375 3350);
FORCEPROP 1 LAST OFFPAGE TRUE
J 0
(3700 3225);
DISPLAY 1.404255 (3700 3225);
PAINT GREEN (3700 3225);
DISPLAY INVISIBLE (3700 3225);
FORCEPROP 1 LAST COMMENT_BODY TRUE
J 0
(3330 3255);
DISPLAY 1.404255 (3330 3255);
PAINT PEACH (3330 3255);
DISPLAY INVISIBLE (3330 3255);
FORCEPROP 2 LAST PATH I11
J 0
(3575 3400);
DISPLAY 1.021277 (3575 3400);
PAINT ORANGE (3575 3400);
DISPLAY INVISIBLE (3575 3400);
FORCEADD OFFPAGE..2
(3375 1800);
FORCEPROP 2 LAST $XR0 55 
J 0
(3564 1800);
DISPLAY 0.638298 (3564 1800);
PAINT MONO (3564 1800);
FORCEPROP 2 LAST CDS_LIB mstr_standard
J 0
(3375 1800);
PAINT ORANGE (3375 1800);
DISPLAY INVISIBLE (3375 1800);
FORCEPROP 1 LAST OFFPAGE TRUE
J 0
(3700 1675);
DISPLAY 1.404255 (3700 1675);
PAINT GREEN (3700 1675);
DISPLAY INVISIBLE (3700 1675);
FORCEPROP 1 LAST COMMENT_BODY TRUE
J 0
(3330 1705);
DISPLAY 1.404255 (3330 1705);
PAINT PEACH (3330 1705);
DISPLAY INVISIBLE (3330 1705);
FORCEPROP 2 LAST PATH I14
J 0
(3575 1850);
DISPLAY 1.021277 (3575 1850);
PAINT ORANGE (3575 1850);
DISPLAY INVISIBLE (3575 1850);
FORCEADD OFFPAGE..2
(3375 1575);
FORCEPROP 2 LAST $XR0 55 
J 0
(3564 1575);
DISPLAY 0.638298 (3564 1575);
PAINT MONO (3564 1575);
FORCEPROP 2 LAST CDS_LIB mstr_standard
J 0
(3375 1575);
PAINT ORANGE (3375 1575);
DISPLAY INVISIBLE (3375 1575);
FORCEPROP 1 LAST OFFPAGE TRUE
J 0
(3700 1450);
DISPLAY 1.404255 (3700 1450);
PAINT GREEN (3700 1450);
DISPLAY INVISIBLE (3700 1450);
FORCEPROP 1 LAST COMMENT_BODY TRUE
J 0
(3330 1480);
DISPLAY 1.404255 (3330 1480);
PAINT PEACH (3330 1480);
DISPLAY INVISIBLE (3330 1480);
FORCEPROP 2 LAST PATH I15
J 0
(3575 1625);
DISPLAY 1.021277 (3575 1625);
PAINT ORANGE (3575 1625);
DISPLAY INVISIBLE (3575 1625);
FORCEADD OFFPAGE..2
(3375 1350);
FORCEPROP 2 LAST $XR0 55 
J 0
(3564 1350);
DISPLAY 0.638298 (3564 1350);
PAINT MONO (3564 1350);
FORCEPROP 2 LAST CDS_LIB mstr_standard
J 0
(3375 1350);
PAINT ORANGE (3375 1350);
DISPLAY INVISIBLE (3375 1350);
FORCEPROP 1 LAST OFFPAGE TRUE
J 0
(3700 1225);
DISPLAY 1.404255 (3700 1225);
PAINT GREEN (3700 1225);
DISPLAY INVISIBLE (3700 1225);
FORCEPROP 1 LAST COMMENT_BODY TRUE
J 0
(3330 1255);
DISPLAY 1.404255 (3330 1255);
PAINT PEACH (3330 1255);
DISPLAY INVISIBLE (3330 1255);
FORCEPROP 2 LAST PATH I16
J 0
(3575 1400);
DISPLAY 1.021277 (3575 1400);
PAINT ORANGE (3575 1400);
DISPLAY INVISIBLE (3575 1400);
FORCEADD OFFPAGE..2
(3375 1050);
FORCEPROP 2 LAST $XR0 55 
J 0
(3564 1050);
DISPLAY 0.638298 (3564 1050);
PAINT MONO (3564 1050);
FORCEPROP 2 LAST CDS_LIB mstr_standard
J 0
(3375 1050);
PAINT ORANGE (3375 1050);
DISPLAY INVISIBLE (3375 1050);
FORCEPROP 1 LAST OFFPAGE TRUE
J 0
(3700 925);
DISPLAY 1.404255 (3700 925);
PAINT GREEN (3700 925);
DISPLAY INVISIBLE (3700 925);
FORCEPROP 1 LAST COMMENT_BODY TRUE
J 0
(3330 955);
DISPLAY 1.404255 (3330 955);
PAINT PEACH (3330 955);
DISPLAY INVISIBLE (3330 955);
FORCEPROP 2 LAST PATH I17
J 0
(3575 1100);
DISPLAY 1.021277 (3575 1100);
PAINT ORANGE (3575 1100);
DISPLAY INVISIBLE (3575 1100);
FORCEADD RES..2
(1900 4450);
FORCEPROP 1 LASTPIN (1900 4350) $PN 2
J 0
(1905 4360);
DISPLAY 0.617021 (1905 4360);
PAINT WHITE (1905 4360);
FORCEPROP 1 LAST LOCATION R6D12
J 0
(1945 4575);
DISPLAY 0.617021 (1945 4575);
PAINT AQUA (1945 4575);
FORCEPROP 1 LAST PART_NUMBER G21796-047
J 0
(1940 4325);
DISPLAY 0.617021 (1940 4325);
PAINT BLUE (1940 4325);
FORCEPROP 1 LAST VALUE 49.9
J 0
(1945 4525);
DISPLAY 0.617021 (1945 4525);
PAINT SKYBLUE (1945 4525);
FORCEPROP 1 LAST TOLERANCE 1%
J 0
(1945 4475);
DISPLAY 0.617021 (1945 4475);
PAINT SKYBLUE (1945 4475);
FORCEPROP 1 LAST PACK_TYPE 0402
J 0
(1940 4275);
DISPLAY 0.617021 (1940 4275);
PAINT SKYBLUE (1940 4275);
FORCEPROP 1 LAST MATERIAL CHIP
J 0
(1940 4375);
DISPLAY 0.617021 (1940 4375);
PAINT SKYBLUE (1940 4375);
FORCEPROP 1 LAST WATTAGE 1/16W
J 0
(1940 4425);
DISPLAY 0.617021 (1940 4425);
PAINT SKYBLUE (1940 4425);
FORCEPROP 1 LASTPIN (1900 4550) $PN 1
J 0
(1905 4512);
DISPLAY 0.617021 (1905 4512);
PAINT WHITE (1905 4512);
FORCEPROP 2 LAST BOM_COST PROC_SIDEBAND
J 0
(1900 4450);
DISPLAY 1.617021 (1900 4450);
PAINT WHITE (1900 4450);
DISPLAY INVISIBLE (1900 4450);
FORCEPROP 2 LAST CDS_LIB mstr_discrete
J 0
(1900 4450);
DISPLAY 1.617021 (1900 4450);
PAINT ORANGE (1900 4450);
DISPLAY INVISIBLE (1900 4450);
FORCEPROP 2 LAST SEC_TYPE 0402
J 0
(1950 4675);
DISPLAY 1.617021 (1950 4675);
PAINT MONO (1950 4675);
DISPLAY INVISIBLE (1950 4675);
FORCEPROP 2 LAST SEC 1
J 0
(1950 4675);
DISPLAY 1.510638 (1950 4675);
PAINT MONO (1950 4675);
DISPLAY INVISIBLE (1950 4675);
FORCEPROP 2 LAST CDS_LOCATION R6D12
J 0
(1945 4575);
DISPLAY 0.617021 (1945 4575);
PAINT AQUA (1945 4575);
DISPLAY INVISIBLE (1945 4575);
FORCEPROP 1 LAST PATH I2
J 0
(1950 4625);
DISPLAY 0.978723 (1950 4625);
PAINT WHITE (1950 4625);
DISPLAY INVISIBLE (1950 4625);
FORCEPROP 2 LAST ROOM PROC_RSTS_PGOODS
J 0
(1925 4225);
DISPLAY 1.617021 (1925 4225);
PAINT WHITE (1925 4225);
DISPLAY INVISIBLE (1925 4225);
FORCEADD PVCCIO_CPU1..1
(1800 2425);
FORCEPROP 3 LASTPIN (1800 2375) SIG_NAME PVCCIO_CPU1\g
J 0
(1810 2385);
DISPLAY 0.659574 (1810 2385);
PAINT MONO (1810 2385);
DISPLAY INVISIBLE (1810 2385);
FORCEPROP 1 LAST VOLTAGE 1.1V
J 0
(1755 2382);
DISPLAY 0.340426 (1755 2382);
PAINT SKYBLUE (1755 2382);
DISPLAY INVISIBLE (1755 2382);
FORCEPROP 2 LAST CDS_LIB mstr_symbols
J 0
(1800 2425);
PAINT ORANGE (1800 2425);
DISPLAY INVISIBLE (1800 2425);
FORCEPROP 1 LAST BODY_TYPE PLUMBING
J 0
(1755 2382);
DISPLAY 0.340426 (1755 2382);
PAINT GREEN (1755 2382);
DISPLAY INVISIBLE (1755 2382);
FORCEPROP 1 LAST PATH I24
J 0
(1850 2450);
DISPLAY 0.872340 (1850 2450);
PAINT AQUA (1850 2450);
DISPLAY INVISIBLE (1850 2450);
FORCEPROP 1 LAST HDL_POWER PVCCIO_CPU1
J 1
(1800 2475);
DISPLAY 0.872340 (1800 2475);
PAINT GREEN (1800 2475);
DISPLAY INVISIBLE (1800 2475);
FORCEADD RES..2
(1900 2150);
FORCEPROP 1 LAST LOCATION R3D20
J 0
(1945 2275);
DISPLAY 0.617021 (1945 2275);
PAINT AQUA (1945 2275);
FORCEPROP 1 LAST PART_NUMBER G21796-047
J 0
(1940 2025);
DISPLAY 0.617021 (1940 2025);
PAINT BLUE (1940 2025);
FORCEPROP 1 LAST VALUE 49.9
J 0
(1945 2225);
DISPLAY 0.617021 (1945 2225);
PAINT SKYBLUE (1945 2225);
FORCEPROP 1 LAST TOLERANCE 1%
J 0
(1945 2175);
DISPLAY 0.617021 (1945 2175);
PAINT SKYBLUE (1945 2175);
FORCEPROP 1 LAST PACK_TYPE 0402
J 0
(1940 1975);
DISPLAY 0.617021 (1940 1975);
PAINT SKYBLUE (1940 1975);
FORCEPROP 1 LAST MATERIAL CHIP
J 0
(1940 2075);
DISPLAY 0.617021 (1940 2075);
PAINT SKYBLUE (1940 2075);
FORCEPROP 1 LAST WATTAGE 1/16W
J 0
(1940 2125);
DISPLAY 0.617021 (1940 2125);
PAINT SKYBLUE (1940 2125);
FORCEPROP 1 LASTPIN (1900 2050) $PN 2
J 0
(1905 2060);
DISPLAY 0.617021 (1905 2060);
PAINT WHITE (1905 2060);
FORCEPROP 1 LASTPIN (1900 2250) $PN 1
J 0
(1905 2212);
DISPLAY 0.617021 (1905 2212);
PAINT WHITE (1905 2212);
FORCEPROP 2 LAST BOM_COST PROC_SIDEBAND
J 0
(1900 2150);
DISPLAY 1.617021 (1900 2150);
PAINT WHITE (1900 2150);
DISPLAY INVISIBLE (1900 2150);
FORCEPROP 2 LAST CDS_LIB mstr_discrete
J 0
(1900 2150);
DISPLAY 1.617021 (1900 2150);
PAINT ORANGE (1900 2150);
DISPLAY INVISIBLE (1900 2150);
FORCEPROP 2 LAST SEC_TYPE 0402
J 0
(1950 2375);
DISPLAY 1.617021 (1950 2375);
PAINT MONO (1950 2375);
DISPLAY INVISIBLE (1950 2375);
FORCEPROP 2 LAST SEC 1
J 0
(1950 2375);
DISPLAY 1.510638 (1950 2375);
PAINT MONO (1950 2375);
DISPLAY INVISIBLE (1950 2375);
FORCEPROP 2 LAST CDS_LOCATION R3D20
J 0
(1945 2275);
DISPLAY 0.617021 (1945 2275);
PAINT AQUA (1945 2275);
DISPLAY INVISIBLE (1945 2275);
FORCEPROP 1 LAST PATH I25
J 0
(1950 2325);
DISPLAY 0.978723 (1950 2325);
PAINT WHITE (1950 2325);
DISPLAY INVISIBLE (1950 2325);
FORCEPROP 2 LAST ROOM PROC_RSTS_PGOODS
J 0
(1925 1925);
DISPLAY 1.617021 (1925 1925);
PAINT WHITE (1925 1925);
DISPLAY INVISIBLE (1925 1925);
FORCEADD RES..2
R 2
(1700 2150);
FORCEPROP 1 LAST LOCATION R3D15
J 2
(1655 2275);
DISPLAY 0.617021 (1655 2275);
PAINT AQUA (1655 2275);
FORCEPROP 1 LAST PART_NUMBER G21796-047
J 2
(1660 2025);
DISPLAY 0.617021 (1660 2025);
PAINT BLUE (1660 2025);
FORCEPROP 1 LAST VALUE 49.9
J 2
(1655 2225);
DISPLAY 0.617021 (1655 2225);
PAINT SKYBLUE (1655 2225);
FORCEPROP 1 LAST TOLERANCE 1%
J 2
(1655 2175);
DISPLAY 0.617021 (1655 2175);
PAINT SKYBLUE (1655 2175);
FORCEPROP 1 LAST PACK_TYPE 0402
J 2
(1660 1975);
DISPLAY 0.617021 (1660 1975);
PAINT SKYBLUE (1660 1975);
FORCEPROP 1 LAST MATERIAL CHIP
J 2
(1660 2075);
DISPLAY 0.617021 (1660 2075);
PAINT SKYBLUE (1660 2075);
FORCEPROP 1 LAST WATTAGE 1/16W
J 2
(1660 2125);
DISPLAY 0.617021 (1660 2125);
PAINT SKYBLUE (1660 2125);
FORCEPROP 1 LASTPIN (1700 2050) $PN 2
J 2
(1695 2060);
DISPLAY 0.617021 (1695 2060);
PAINT WHITE (1695 2060);
FORCEPROP 1 LASTPIN (1700 2250) $PN 1
J 2
(1695 2212);
DISPLAY 0.617021 (1695 2212);
PAINT WHITE (1695 2212);
FORCEPROP 2 LAST BOM_COST PROC_SIDEBAND
J 2
(1700 2150);
DISPLAY 1.617021 (1700 2150);
PAINT WHITE (1700 2150);
DISPLAY INVISIBLE (1700 2150);
FORCEPROP 2 LAST CDS_LIB mstr_discrete
J 2
(1700 2150);
DISPLAY 1.617021 (1700 2150);
PAINT ORANGE (1700 2150);
DISPLAY INVISIBLE (1700 2150);
FORCEPROP 2 LAST SEC_TYPE 0402
J 2
(1650 2375);
DISPLAY 1.617021 (1650 2375);
PAINT MONO (1650 2375);
DISPLAY INVISIBLE (1650 2375);
FORCEPROP 2 LAST SEC 1
J 2
(1650 2375);
DISPLAY 1.510638 (1650 2375);
PAINT MONO (1650 2375);
DISPLAY INVISIBLE (1650 2375);
FORCEPROP 2 LAST CDS_LOCATION R3D15
J 2
(1655 2275);
DISPLAY 0.617021 (1655 2275);
PAINT AQUA (1655 2275);
DISPLAY INVISIBLE (1655 2275);
FORCEPROP 1 LAST PATH I26
J 2
(1650 2325);
DISPLAY 0.978723 (1650 2325);
PAINT WHITE (1650 2325);
DISPLAY INVISIBLE (1650 2325);
FORCEPROP 2 LAST ROOM PROC_RSTS_PGOODS
J 2
(1675 1925);
DISPLAY 1.617021 (1675 1925);
PAINT WHITE (1675 1925);
DISPLAY INVISIBLE (1675 1925);
FORCEADD PVDDQ_KLM..1
(975 2400);
FORCEPROP 3 LASTPIN (975 2350) SIG_NAME PVDDQ_KLM\g
J 0
(985 2360);
DISPLAY 0.659574 (985 2360);
PAINT MONO (985 2360);
DISPLAY INVISIBLE (985 2360);
FORCEPROP 1 LAST VOLTAGE 1.2V
J 0
(930 2357);
DISPLAY 0.340426 (930 2357);
PAINT SKYBLUE (930 2357);
DISPLAY INVISIBLE (930 2357);
FORCEPROP 2 LAST CDS_LIB mstr_symbols
J 0
(975 2400);
PAINT ORANGE (975 2400);
DISPLAY INVISIBLE (975 2400);
FORCEPROP 1 LAST BODY_TYPE PLUMBING
J 0
(930 2357);
DISPLAY 0.340426 (930 2357);
PAINT GREEN (930 2357);
DISPLAY INVISIBLE (930 2357);
FORCEPROP 1 LAST PATH I27
J 0
(1025 2425);
DISPLAY 0.872340 (1025 2425);
PAINT AQUA (1025 2425);
DISPLAY INVISIBLE (1025 2425);
FORCEPROP 1 LAST HDL_POWER PVDDQ_KLM
J 1
(975 2450);
DISPLAY 0.872340 (975 2450);
PAINT GREEN (975 2450);
DISPLAY INVISIBLE (975 2450);
FORCEADD RES..2
(975 2150);
FORCEPROP 1 LAST LOCATION R7M9
J 0
(1020 2275);
DISPLAY 0.617021 (1020 2275);
PAINT AQUA (1020 2275);
FORCEPROP 1 LAST PART_NUMBER G21796-298
J 0
(1015 2025);
DISPLAY 0.617021 (1015 2025);
PAINT BLUE (1015 2025);
FORCEPROP 1 LAST VALUE 64.9
J 0
(1020 2225);
DISPLAY 0.617021 (1020 2225);
PAINT SKYBLUE (1020 2225);
FORCEPROP 1 LAST TOLERANCE 1.0%
J 0
(1020 2175);
DISPLAY 0.617021 (1020 2175);
PAINT SKYBLUE (1020 2175);
FORCEPROP 1 LAST PACK_TYPE 0402
J 0
(1015 1975);
DISPLAY 0.617021 (1015 1975);
PAINT SKYBLUE (1015 1975);
FORCEPROP 1 LAST MATERIAL CHIP
J 0
(1015 2075);
DISPLAY 0.617021 (1015 2075);
PAINT SKYBLUE (1015 2075);
FORCEPROP 1 LAST WATTAGE 1/16W
J 0
(1015 2125);
DISPLAY 0.617021 (1015 2125);
PAINT SKYBLUE (1015 2125);
FORCEPROP 1 LASTPIN (975 2050) $PN 2
J 0
(980 2060);
DISPLAY 0.617021 (980 2060);
PAINT WHITE (980 2060);
FORCEPROP 1 LASTPIN (975 2250) $PN 1
J 0
(980 2212);
DISPLAY 0.617021 (980 2212);
PAINT WHITE (980 2212);
FORCEPROP 2 LAST BOM_COST PROC_SIDEBAND
J 0
(1025 2325);
DISPLAY 1.659574 (1025 2325);
PAINT WHITE (1025 2325);
DISPLAY INVISIBLE (1025 2325);
FORCEPROP 2 LAST CDS_LIB mstr_discrete
J 0
(975 2150);
DISPLAY 1.617021 (975 2150);
PAINT ORANGE (975 2150);
DISPLAY INVISIBLE (975 2150);
FORCEPROP 2 LAST CDS_SEC 1
J 0
(1025 2375);
DISPLAY 2.276596 (1025 2375);
PAINT ORANGE (1025 2375);
DISPLAY INVISIBLE (1025 2375);
FORCEPROP 2 LAST $SEC 1
J 0
(1025 2375);
DISPLAY 1.510638 (1025 2375);
PAINT MONO (1025 2375);
DISPLAY INVISIBLE (1025 2375);
FORCEPROP 2 LAST CDS_LOCATION R7M9
J 0
(1020 2275);
DISPLAY 0.617021 (1020 2275);
PAINT AQUA (1020 2275);
DISPLAY INVISIBLE (1020 2275);
FORCEPROP 1 LAST PATH I28
J 0
(1025 2325);
DISPLAY 0.978723 (1025 2325);
PAINT WHITE (1025 2325);
DISPLAY INVISIBLE (1025 2325);
FORCEPROP 2 LAST ROOM PROC_RSTS_PGOODS
J 0
(1025 2325);
DISPLAY 2.276596 (1025 2325);
PAINT WHITE (1025 2325);
DISPLAY INVISIBLE (1025 2325);
FORCEADD PVDDQ_GHJ..1
(575 2400);
FORCEPROP 3 LASTPIN (575 2350) SIG_NAME PVDDQ_GHJ\g
J 0
(585 2360);
DISPLAY 0.659574 (585 2360);
PAINT MONO (585 2360);
DISPLAY INVISIBLE (585 2360);
FORCEPROP 1 LAST VOLTAGE 1.2V
J 0
(530 2357);
DISPLAY 0.340426 (530 2357);
PAINT SKYBLUE (530 2357);
DISPLAY INVISIBLE (530 2357);
FORCEPROP 2 LAST CDS_LIB mstr_symbols
J 0
(575 2400);
PAINT ORANGE (575 2400);
DISPLAY INVISIBLE (575 2400);
FORCEPROP 1 LAST BODY_TYPE PLUMBING
J 0
(530 2357);
DISPLAY 0.340426 (530 2357);
PAINT GREEN (530 2357);
DISPLAY INVISIBLE (530 2357);
FORCEPROP 1 LAST PATH I29
J 0
(625 2425);
DISPLAY 0.872340 (625 2425);
PAINT AQUA (625 2425);
DISPLAY INVISIBLE (625 2425);
FORCEPROP 1 LAST HDL_POWER PVDDQ_GHJ
J 1
(575 2450);
DISPLAY 0.872340 (575 2450);
PAINT GREEN (575 2450);
DISPLAY INVISIBLE (575 2450);
FORCEADD RES..2
R 2
(1700 4450);
FORCEPROP 1 LAST LOCATION R6D8
J 2
(1655 4575);
DISPLAY 0.617021 (1655 4575);
PAINT AQUA (1655 4575);
FORCEPROP 1 LAST PART_NUMBER G21796-047
J 2
(1660 4325);
DISPLAY 0.617021 (1660 4325);
PAINT BLUE (1660 4325);
FORCEPROP 1 LAST VALUE 49.9
J 2
(1655 4525);
DISPLAY 0.617021 (1655 4525);
PAINT SKYBLUE (1655 4525);
FORCEPROP 1 LAST TOLERANCE 1%
J 2
(1655 4475);
DISPLAY 0.617021 (1655 4475);
PAINT SKYBLUE (1655 4475);
FORCEPROP 1 LAST PACK_TYPE 0402
J 2
(1660 4275);
DISPLAY 0.617021 (1660 4275);
PAINT SKYBLUE (1660 4275);
FORCEPROP 1 LAST MATERIAL CHIP
J 2
(1660 4375);
DISPLAY 0.617021 (1660 4375);
PAINT SKYBLUE (1660 4375);
FORCEPROP 1 LAST WATTAGE 1/16W
J 2
(1660 4425);
DISPLAY 0.617021 (1660 4425);
PAINT SKYBLUE (1660 4425);
FORCEPROP 1 LASTPIN (1700 4350) $PN 2
J 2
(1695 4360);
DISPLAY 0.617021 (1695 4360);
PAINT WHITE (1695 4360);
FORCEPROP 1 LASTPIN (1700 4550) $PN 1
J 2
(1695 4512);
DISPLAY 0.617021 (1695 4512);
PAINT WHITE (1695 4512);
FORCEPROP 2 LAST BOM_COST PROC_SIDEBAND
J 2
(1700 4450);
DISPLAY 1.617021 (1700 4450);
PAINT WHITE (1700 4450);
DISPLAY INVISIBLE (1700 4450);
FORCEPROP 2 LAST CDS_LIB mstr_discrete
J 2
(1700 4450);
DISPLAY 1.617021 (1700 4450);
PAINT ORANGE (1700 4450);
DISPLAY INVISIBLE (1700 4450);
FORCEPROP 2 LAST SEC_TYPE 0402
J 2
(1650 4675);
DISPLAY 1.617021 (1650 4675);
PAINT MONO (1650 4675);
DISPLAY INVISIBLE (1650 4675);
FORCEPROP 2 LAST SEC 1
J 2
(1650 4675);
DISPLAY 1.510638 (1650 4675);
PAINT MONO (1650 4675);
DISPLAY INVISIBLE (1650 4675);
FORCEPROP 2 LAST CDS_LOCATION R6D8
J 2
(1655 4575);
DISPLAY 0.617021 (1655 4575);
PAINT AQUA (1655 4575);
DISPLAY INVISIBLE (1655 4575);
FORCEPROP 1 LAST PATH I3
J 2
(1650 4625);
DISPLAY 0.978723 (1650 4625);
PAINT WHITE (1650 4625);
DISPLAY INVISIBLE (1650 4625);
FORCEPROP 2 LAST ROOM PROC_RSTS_PGOODS
J 2
(1675 4225);
DISPLAY 1.617021 (1675 4225);
PAINT WHITE (1675 4225);
DISPLAY INVISIBLE (1675 4225);
FORCEADD RES..2
(575 2150);
FORCEPROP 1 LAST LOCATION R3D21
J 0
(620 2275);
DISPLAY 0.617021 (620 2275);
PAINT AQUA (620 2275);
FORCEPROP 1 LAST PART_NUMBER G21796-298
J 0
(615 2025);
DISPLAY 0.617021 (615 2025);
PAINT BLUE (615 2025);
FORCEPROP 1 LAST VALUE 64.9
J 0
(620 2225);
DISPLAY 0.617021 (620 2225);
PAINT SKYBLUE (620 2225);
FORCEPROP 1 LAST TOLERANCE 1.0%
J 0
(620 2175);
DISPLAY 0.617021 (620 2175);
PAINT SKYBLUE (620 2175);
FORCEPROP 1 LAST PACK_TYPE 0402
J 0
(615 1975);
DISPLAY 0.617021 (615 1975);
PAINT SKYBLUE (615 1975);
FORCEPROP 1 LAST MATERIAL CHIP
J 0
(615 2075);
DISPLAY 0.617021 (615 2075);
PAINT SKYBLUE (615 2075);
FORCEPROP 1 LAST WATTAGE 1/16W
J 0
(615 2125);
DISPLAY 0.617021 (615 2125);
PAINT SKYBLUE (615 2125);
FORCEPROP 1 LASTPIN (575 2050) $PN 2
J 0
(580 2060);
DISPLAY 0.617021 (580 2060);
PAINT WHITE (580 2060);
FORCEPROP 1 LASTPIN (575 2250) $PN 1
J 0
(580 2212);
DISPLAY 0.617021 (580 2212);
PAINT WHITE (580 2212);
FORCEPROP 2 LAST BOM_COST PROC_SIDEBAND
J 0
(625 2325);
DISPLAY 1.659574 (625 2325);
PAINT WHITE (625 2325);
DISPLAY INVISIBLE (625 2325);
FORCEPROP 2 LAST CDS_LIB mstr_discrete
J 0
(575 2150);
DISPLAY 1.617021 (575 2150);
PAINT ORANGE (575 2150);
DISPLAY INVISIBLE (575 2150);
FORCEPROP 2 LAST CDS_SEC 1
J 0
(625 2375);
DISPLAY 2.276596 (625 2375);
PAINT ORANGE (625 2375);
DISPLAY INVISIBLE (625 2375);
FORCEPROP 2 LAST $SEC 1
J 0
(625 2375);
DISPLAY 1.510638 (625 2375);
PAINT MONO (625 2375);
DISPLAY INVISIBLE (625 2375);
FORCEPROP 2 LAST CDS_LOCATION R3D21
J 0
(620 2275);
DISPLAY 0.617021 (620 2275);
PAINT AQUA (620 2275);
DISPLAY INVISIBLE (620 2275);
FORCEPROP 1 LAST PATH I30
J 0
(625 2325);
DISPLAY 0.978723 (625 2325);
PAINT WHITE (625 2325);
DISPLAY INVISIBLE (625 2325);
FORCEPROP 2 LAST ROOM PROC_RSTS_PGOODS
J 0
(625 2325);
DISPLAY 2.276596 (625 2325);
PAINT WHITE (625 2325);
DISPLAY INVISIBLE (625 2325);
FORCEADD RES..2
(-2100 4650);
FORCEPROP 1 LAST LOCATION R3P36
J 0
(-2055 4775);
DISPLAY 0.617021 (-2055 4775);
PAINT AQUA (-2055 4775);
FORCEPROP 1 LAST PACK_TYPE 0402
J 0
(-2060 4475);
DISPLAY 0.617021 (-2060 4475);
PAINT SKYBLUE (-2060 4475);
FORCEPROP 1 LAST PART_NUMBER G21796-026
J 0
(-2060 4525);
DISPLAY 0.617021 (-2060 4525);
PAINT BLUE (-2060 4525);
FORCEPROP 1 LAST VALUE 1.00K
J 0
(-2055 4725);
DISPLAY 0.617021 (-2055 4725);
PAINT SKYBLUE (-2055 4725);
FORCEPROP 1 LAST TOLERANCE 1%
J 0
(-2055 4675);
DISPLAY 0.617021 (-2055 4675);
PAINT SKYBLUE (-2055 4675);
FORCEPROP 1 LAST MATERIAL CHIP
J 0
(-2060 4575);
DISPLAY 0.617021 (-2060 4575);
PAINT SKYBLUE (-2060 4575);
FORCEPROP 1 LAST WATTAGE 1/16W
J 0
(-2060 4625);
DISPLAY 0.617021 (-2060 4625);
PAINT SKYBLUE (-2060 4625);
FORCEPROP 1 LASTPIN (-2100 4550) $PN 2
J 0
(-2095 4560);
DISPLAY 0.617021 (-2095 4560);
PAINT WHITE (-2095 4560);
FORCEPROP 1 LASTPIN (-2100 4750) $PN 1
J 0
(-2095 4712);
DISPLAY 0.617021 (-2095 4712);
PAINT WHITE (-2095 4712);
FORCEPROP 2 LAST BOM_COST PROC_SIDEBAND
J 0
(-2100 4650);
DISPLAY 1.617021 (-2100 4650);
PAINT WHITE (-2100 4650);
DISPLAY INVISIBLE (-2100 4650);
FORCEPROP 2 LAST CDS_LIB mstr_discrete
J 0
(-2100 4650);
DISPLAY 1.617021 (-2100 4650);
PAINT ORANGE (-2100 4650);
DISPLAY INVISIBLE (-2100 4650);
FORCEPROP 2 LAST CDS_SEC 1
J 0
(-2050 4875);
DISPLAY 2.276596 (-2050 4875);
PAINT ORANGE (-2050 4875);
DISPLAY INVISIBLE (-2050 4875);
FORCEPROP 2 LAST $SEC 1
J 0
(-2050 4875);
DISPLAY 1.510638 (-2050 4875);
PAINT MONO (-2050 4875);
DISPLAY INVISIBLE (-2050 4875);
FORCEPROP 2 LAST CDS_LOCATION R3P36
J 0
(-2055 4775);
DISPLAY 0.617021 (-2055 4775);
PAINT AQUA (-2055 4775);
DISPLAY INVISIBLE (-2055 4775);
FORCEPROP 1 LAST PATH I36
J 0
(-2050 4825);
DISPLAY 0.978723 (-2050 4825);
PAINT WHITE (-2050 4825);
DISPLAY INVISIBLE (-2050 4825);
FORCEPROP 2 LAST ROOM PROC_RSTS_PGOODS
J 0
(-2075 4425);
DISPLAY 1.617021 (-2075 4425);
PAINT WHITE (-2075 4425);
DISPLAY INVISIBLE (-2075 4425);
FORCEADD PVDDQ_DEF..1
(975 4700);
FORCEPROP 3 LASTPIN (975 4650) SIG_NAME PVDDQ_DEF\g
J 0
(985 4660);
DISPLAY 0.659574 (985 4660);
PAINT MONO (985 4660);
DISPLAY INVISIBLE (985 4660);
FORCEPROP 1 LAST VOLTAGE 1.2V
J 0
(930 4657);
DISPLAY 0.340426 (930 4657);
PAINT SKYBLUE (930 4657);
DISPLAY INVISIBLE (930 4657);
FORCEPROP 2 LAST CDS_LIB mstr_symbols
J 0
(975 4700);
PAINT ORANGE (975 4700);
DISPLAY INVISIBLE (975 4700);
FORCEPROP 1 LAST BODY_TYPE PLUMBING
J 0
(930 4657);
DISPLAY 0.340426 (930 4657);
PAINT GREEN (930 4657);
DISPLAY INVISIBLE (930 4657);
FORCEPROP 1 LAST PATH I4
J 0
(1025 4725);
DISPLAY 0.872340 (1025 4725);
PAINT AQUA (1025 4725);
DISPLAY INVISIBLE (1025 4725);
FORCEPROP 1 LAST HDL_POWER PVDDQ_DEF
J 1
(975 4750);
DISPLAY 0.872340 (975 4750);
PAINT GREEN (975 4750);
DISPLAY INVISIBLE (975 4750);
FORCEADD GND..1
(-325 3550);
FORCEPROP 3 LASTPIN (-325 3600) SIG_NAME GND\g
J 0
(-315 3610);
DISPLAY 0.659574 (-315 3610);
PAINT MONO (-315 3610);
DISPLAY INVISIBLE (-315 3610);
FORCEPROP 1 LAST VOLTAGE 0.0V
J 0
(-370 3507);
DISPLAY 0.340426 (-370 3507);
PAINT SKYBLUE (-370 3507);
DISPLAY INVISIBLE (-370 3507);
FORCEPROP 1 LAST SIZE 1B
J 0
(-250 3500);
DISPLAY 1.893617 (-250 3500);
PAINT GREEN (-250 3500);
DISPLAY INVISIBLE (-250 3500);
FORCEPROP 2 LAST CDS_LIB mstr_symbols
J 0
(-325 3550);
PAINT ORANGE (-325 3550);
DISPLAY INVISIBLE (-325 3550);
FORCEPROP 1 LAST BODY_TYPE PLUMBING
J 0
(-370 3507);
DISPLAY 0.340426 (-370 3507);
PAINT GREEN (-370 3507);
DISPLAY INVISIBLE (-370 3507);
FORCEPROP 1 LAST PATH I41
J 0
(-250 3550);
DISPLAY 0.872340 (-250 3550);
PAINT AQUA (-250 3550);
DISPLAY INVISIBLE (-250 3550);
FORCEPROP 1 LAST HDL_POWER GND
J 0
(-325 3700);
DISPLAY 1.595745 (-325 3700);
PAINT GREEN (-325 3700);
DISPLAY INVISIBLE (-325 3700);
FORCEADD GTL2014..1
(-875 4100);
FORCEPROP 1 LAST LOCATION U3P1
J 0
(-1275 4650);
DISPLAY 0.617021 (-1275 4650);
PAINT AQUA (-1275 4650);
FORCEPROP 1 LAST MATERIAL IC
J 0
(-1275 4600);
DISPLAY 0.617021 (-1275 4600);
PAINT SKYBLUE (-1275 4600);
FORCEPROP 2 LASTPIN (-1325 4350) $PN 4
J 2
(-1335 4360);
DISPLAY 0.617021 (-1335 4360);
PAINT WHITE (-1335 4360);
FORCEPROP 2 LASTPIN (-1325 4400) $PN 14
J 2
(-1335 4410);
DISPLAY 0.617021 (-1335 4410);
PAINT WHITE (-1335 4410);
FORCEPROP 2 LASTPIN (-425 3800) $PN 11
J 0
(-415 3810);
DISPLAY 0.617021 (-415 3810);
PAINT WHITE (-415 3810);
FORCEPROP 2 LASTPIN (-425 3750) $PN 8
J 0
(-415 3760);
DISPLAY 0.617021 (-415 3760);
PAINT WHITE (-415 3760);
FORCEPROP 2 LASTPIN (-425 3700) $PN 7
J 0
(-415 3710);
DISPLAY 0.617021 (-415 3710);
PAINT WHITE (-415 3710);
FORCEPROP 2 LASTPIN (-1325 4250) $PN 1
J 2
(-1335 4260);
DISPLAY 0.617021 (-1335 4260);
PAINT WHITE (-1335 4260);
FORCEPROP 2 LASTPIN (-425 4100) $PN 6
J 0
(-415 4110);
DISPLAY 0.617021 (-415 4110);
PAINT WHITE (-415 4110);
FORCEPROP 2 LASTPIN (-425 4050) $PN 5
J 0
(-415 4060);
DISPLAY 0.617021 (-415 4060);
PAINT WHITE (-415 4060);
FORCEPROP 2 LASTPIN (-425 4000) $PN 3
J 0
(-415 4010);
DISPLAY 0.617021 (-415 4010);
PAINT WHITE (-415 4010);
FORCEPROP 2 LASTPIN (-425 3950) $PN 2
J 0
(-415 3960);
DISPLAY 0.617021 (-415 3960);
PAINT WHITE (-415 3960);
FORCEPROP 2 LASTPIN (-1325 4100) $PN 9
J 2
(-1335 4110);
DISPLAY 0.617021 (-1335 4110);
PAINT WHITE (-1335 4110);
FORCEPROP 2 LASTPIN (-1325 4050) $PN 10
J 2
(-1335 4060);
DISPLAY 0.617021 (-1335 4060);
PAINT WHITE (-1335 4060);
FORCEPROP 2 LASTPIN (-1325 4000) $PN 12
J 2
(-1335 4010);
DISPLAY 0.617021 (-1335 4010);
PAINT WHITE (-1335 4010);
FORCEPROP 2 LASTPIN (-1325 3950) $PN 13
J 2
(-1335 3960);
DISPLAY 0.617021 (-1335 3960);
PAINT WHITE (-1335 3960);
FORCEPROP 1 LAST PART_NUMBER D66151-001
J 0
(-975 3600);
DISPLAY 0.617021 (-975 3600);
PAINT BLUE (-975 3600);
FORCEPROP 1 LAST PACK_TYPE SM
J 0
(-1275 4700);
DISPLAY 1.617021 (-1275 4700);
PAINT SKYBLUE (-1275 4700);
DISPLAY INVISIBLE (-1275 4700);
FORCEPROP 2 LAST BOM_COST PROC_SIDEBAND
J 0
(-875 4100);
DISPLAY 1.617021 (-875 4100);
PAINT WHITE (-875 4100);
DISPLAY INVISIBLE (-875 4100);
FORCEPROP 2 LAST CDS_LIB mstr_digital
J 0
(-875 4100);
DISPLAY 1.617021 (-875 4100);
PAINT MONO (-875 4100);
DISPLAY INVISIBLE (-875 4100);
FORCEPROP 2 LAST CDS_SEC 1
J 2
(-1275 4700);
DISPLAY 2.276596 (-1275 4700);
PAINT ORANGE (-1275 4700);
DISPLAY INVISIBLE (-1275 4700);
FORCEPROP 2 LAST $SEC 1
J 2
(-1275 4700);
DISPLAY 1.510638 (-1275 4700);
PAINT MONO (-1275 4700);
DISPLAY INVISIBLE (-1275 4700);
FORCEPROP 2 LAST CDS_LOCATION U3P1
J 0
(-1275 4650);
DISPLAY 0.617021 (-1275 4650);
PAINT AQUA (-1275 4650);
DISPLAY INVISIBLE (-1275 4650);
FORCEPROP 1 LAST PATH I42
J 0
(-875 4600);
PAINT GREEN (-875 4600);
DISPLAY INVISIBLE (-875 4600);
FORCEPROP 2 LAST ROOM PROC_RSTS_PGOODS
J 2
(-1275 4700);
DISPLAY 2.276596 (-1275 4700);
PAINT WHITE (-1275 4700);
DISPLAY INVISIBLE (-1275 4700);
FORCEADD GND..1
(-325 1250);
FORCEPROP 3 LASTPIN (-325 1300) SIG_NAME GND\g
J 0
(-315 1310);
DISPLAY 0.659574 (-315 1310);
PAINT MONO (-315 1310);
DISPLAY INVISIBLE (-315 1310);
FORCEPROP 1 LAST VOLTAGE 0.0V
J 0
(-370 1207);
DISPLAY 0.340426 (-370 1207);
PAINT SKYBLUE (-370 1207);
DISPLAY INVISIBLE (-370 1207);
FORCEPROP 2 LAST CDS_LIB mstr_symbols
J 0
(-325 1250);
PAINT ORANGE (-325 1250);
DISPLAY INVISIBLE (-325 1250);
FORCEPROP 1 LAST SIZE 1B
J 0
(-250 1200);
DISPLAY 1.893617 (-250 1200);
PAINT GREEN (-250 1200);
DISPLAY INVISIBLE (-250 1200);
FORCEPROP 1 LAST BODY_TYPE PLUMBING
J 0
(-370 1207);
DISPLAY 0.340426 (-370 1207);
PAINT GREEN (-370 1207);
DISPLAY INVISIBLE (-370 1207);
FORCEPROP 1 LAST PATH I45
J 0
(-250 1250);
DISPLAY 0.872340 (-250 1250);
PAINT AQUA (-250 1250);
DISPLAY INVISIBLE (-250 1250);
FORCEPROP 1 LAST HDL_POWER GND
J 0
(-325 1400);
DISPLAY 1.595745 (-325 1400);
PAINT GREEN (-325 1400);
DISPLAY INVISIBLE (-325 1400);
FORCEADD GTL2014..1
(-875 1800);
FORCEPROP 1 LAST LOCATION U4C2
J 0
(-1275 2350);
DISPLAY 0.617021 (-1275 2350);
PAINT AQUA (-1275 2350);
FORCEPROP 1 LAST PART_NUMBER D66151-001
J 0
(-975 1300);
DISPLAY 0.617021 (-975 1300);
PAINT BLUE (-975 1300);
FORCEPROP 1 LAST MATERIAL IC
J 0
(-1275 2300);
DISPLAY 0.617021 (-1275 2300);
PAINT SKYBLUE (-1275 2300);
FORCEPROP 2 LASTPIN (-1325 2050) $PN 4
J 2
(-1335 2060);
DISPLAY 0.617021 (-1335 2060);
PAINT WHITE (-1335 2060);
FORCEPROP 2 LASTPIN (-1325 2100) $PN 14
J 2
(-1335 2110);
DISPLAY 0.617021 (-1335 2110);
PAINT WHITE (-1335 2110);
FORCEPROP 2 LASTPIN (-425 1500) $PN 11
J 0
(-415 1510);
DISPLAY 0.617021 (-415 1510);
PAINT WHITE (-415 1510);
FORCEPROP 2 LASTPIN (-425 1450) $PN 8
J 0
(-415 1460);
DISPLAY 0.617021 (-415 1460);
PAINT WHITE (-415 1460);
FORCEPROP 2 LASTPIN (-425 1400) $PN 7
J 0
(-415 1410);
DISPLAY 0.617021 (-415 1410);
PAINT WHITE (-415 1410);
FORCEPROP 2 LASTPIN (-1325 1950) $PN 1
J 2
(-1335 1960);
DISPLAY 0.617021 (-1335 1960);
PAINT WHITE (-1335 1960);
FORCEPROP 2 LASTPIN (-425 1800) $PN 6
J 0
(-415 1810);
DISPLAY 0.617021 (-415 1810);
PAINT WHITE (-415 1810);
FORCEPROP 2 LASTPIN (-425 1750) $PN 5
J 0
(-415 1760);
DISPLAY 0.617021 (-415 1760);
PAINT WHITE (-415 1760);
FORCEPROP 2 LASTPIN (-425 1700) $PN 3
J 0
(-415 1710);
DISPLAY 0.617021 (-415 1710);
PAINT WHITE (-415 1710);
FORCEPROP 2 LASTPIN (-425 1650) $PN 2
J 0
(-415 1660);
DISPLAY 0.617021 (-415 1660);
PAINT WHITE (-415 1660);
FORCEPROP 2 LASTPIN (-1325 1800) $PN 9
J 2
(-1335 1810);
DISPLAY 0.617021 (-1335 1810);
PAINT WHITE (-1335 1810);
FORCEPROP 2 LASTPIN (-1325 1750) $PN 10
J 2
(-1335 1760);
DISPLAY 0.617021 (-1335 1760);
PAINT WHITE (-1335 1760);
FORCEPROP 2 LASTPIN (-1325 1700) $PN 12
J 2
(-1335 1710);
DISPLAY 0.617021 (-1335 1710);
PAINT WHITE (-1335 1710);
FORCEPROP 2 LASTPIN (-1325 1650) $PN 13
J 2
(-1335 1660);
DISPLAY 0.617021 (-1335 1660);
PAINT WHITE (-1335 1660);
FORCEPROP 1 LAST PACK_TYPE SM
J 0
(-1275 2400);
DISPLAY 1.617021 (-1275 2400);
PAINT SKYBLUE (-1275 2400);
DISPLAY INVISIBLE (-1275 2400);
FORCEPROP 2 LAST CDS_LIB mstr_digital
J 0
(-875 1800);
DISPLAY 1.617021 (-875 1800);
PAINT MONO (-875 1800);
DISPLAY INVISIBLE (-875 1800);
FORCEPROP 2 LAST BOM_COST PROC_SIDEBAND
J 0
(-875 1800);
DISPLAY 1.617021 (-875 1800);
PAINT WHITE (-875 1800);
DISPLAY INVISIBLE (-875 1800);
FORCEPROP 2 LAST CDS_SEC 1
J 2
(-1275 2400);
DISPLAY 2.276596 (-1275 2400);
PAINT ORANGE (-1275 2400);
DISPLAY INVISIBLE (-1275 2400);
FORCEPROP 2 LAST $SEC 1
J 2
(-1275 2400);
DISPLAY 1.510638 (-1275 2400);
PAINT MONO (-1275 2400);
DISPLAY INVISIBLE (-1275 2400);
FORCEPROP 2 LAST CDS_LOCATION U4C2
J 0
(-1275 2350);
DISPLAY 0.617021 (-1275 2350);
PAINT AQUA (-1275 2350);
DISPLAY INVISIBLE (-1275 2350);
FORCEPROP 1 LAST PATH I46
J 0
(-875 2300);
PAINT GREEN (-875 2300);
DISPLAY INVISIBLE (-875 2300);
FORCEPROP 2 LAST ROOM PROC_RSTS_PGOODS
J 2
(-1275 2400);
DISPLAY 2.276596 (-1275 2400);
PAINT WHITE (-1275 2400);
DISPLAY INVISIBLE (-1275 2400);
FORCEADD RES..2
(975 4450);
FORCEPROP 1 LAST LOCATION R3P29
J 0
(1020 4575);
DISPLAY 0.617021 (1020 4575);
PAINT AQUA (1020 4575);
FORCEPROP 1 LAST PART_NUMBER G21796-298
J 0
(1015 4325);
DISPLAY 0.617021 (1015 4325);
PAINT BLUE (1015 4325);
FORCEPROP 1 LAST VALUE 64.9
J 0
(1020 4525);
DISPLAY 0.617021 (1020 4525);
PAINT SKYBLUE (1020 4525);
FORCEPROP 1 LAST TOLERANCE 1.0%
J 0
(1020 4475);
DISPLAY 0.617021 (1020 4475);
PAINT SKYBLUE (1020 4475);
FORCEPROP 1 LAST PACK_TYPE 0402
J 0
(1015 4275);
DISPLAY 0.617021 (1015 4275);
PAINT SKYBLUE (1015 4275);
FORCEPROP 1 LAST MATERIAL CHIP
J 0
(1015 4375);
DISPLAY 0.617021 (1015 4375);
PAINT SKYBLUE (1015 4375);
FORCEPROP 1 LAST WATTAGE 1/16W
J 0
(1015 4425);
DISPLAY 0.617021 (1015 4425);
PAINT SKYBLUE (1015 4425);
FORCEPROP 1 LASTPIN (975 4350) $PN 2
J 0
(980 4360);
DISPLAY 0.617021 (980 4360);
PAINT WHITE (980 4360);
FORCEPROP 1 LASTPIN (975 4550) $PN 1
J 0
(980 4512);
DISPLAY 0.617021 (980 4512);
PAINT WHITE (980 4512);
FORCEPROP 2 LAST BOM_COST PROC_SIDEBAND
J 0
(1025 4625);
DISPLAY 1.659574 (1025 4625);
PAINT WHITE (1025 4625);
DISPLAY INVISIBLE (1025 4625);
FORCEPROP 2 LAST CDS_LIB mstr_discrete
J 0
(975 4450);
DISPLAY 1.617021 (975 4450);
PAINT ORANGE (975 4450);
DISPLAY INVISIBLE (975 4450);
FORCEPROP 2 LAST CDS_SEC 1
J 0
(1025 4675);
DISPLAY 2.276596 (1025 4675);
PAINT ORANGE (1025 4675);
DISPLAY INVISIBLE (1025 4675);
FORCEPROP 2 LAST $SEC 1
J 0
(1025 4675);
DISPLAY 1.510638 (1025 4675);
PAINT MONO (1025 4675);
DISPLAY INVISIBLE (1025 4675);
FORCEPROP 2 LAST CDS_LOCATION R3P29
J 0
(1020 4575);
DISPLAY 0.617021 (1020 4575);
PAINT AQUA (1020 4575);
DISPLAY INVISIBLE (1020 4575);
FORCEPROP 1 LAST PATH I5
J 0
(1025 4625);
DISPLAY 0.978723 (1025 4625);
PAINT WHITE (1025 4625);
DISPLAY INVISIBLE (1025 4625);
FORCEPROP 2 LAST ROOM PROC_RSTS_PGOODS
J 0
(1025 4625);
DISPLAY 2.276596 (1025 4625);
PAINT WHITE (1025 4625);
DISPLAY INVISIBLE (1025 4625);
FORCEADD OFFPAGE..1
(-2200 4100);
FORCEPROP 2 LAST $XR0 190 
J 0
(-2452 4100);
DISPLAY 0.638298 (-2452 4100);
PAINT MONO (-2452 4100);
FORCEPROP 2 LAST CDS_LIB mstr_standard
J 0
(-2200 4100);
PAINT ORANGE (-2200 4100);
DISPLAY INVISIBLE (-2200 4100);
FORCEPROP 1 LAST OFFPAGE TRUE
J 0
(-1875 3975);
DISPLAY 1.404255 (-1875 3975);
PAINT GREEN (-1875 3975);
DISPLAY INVISIBLE (-1875 3975);
FORCEPROP 1 LAST COMMENT_BODY TRUE
J 0
(-2075 4000);
DISPLAY 1.404255 (-2075 4000);
PAINT PEACH (-2075 4000);
DISPLAY INVISIBLE (-2075 4000);
FORCEPROP 2 LAST PATH I51
J 0
(-2450 4150);
DISPLAY 1.021277 (-2450 4150);
PAINT ORANGE (-2450 4150);
DISPLAY INVISIBLE (-2450 4150);
FORCEADD OFFPAGE..1
(-2200 4050);
FORCEPROP 2 LAST $XR0 190 
J 0
(-2452 4050);
DISPLAY 0.638298 (-2452 4050);
PAINT MONO (-2452 4050);
FORCEPROP 2 LAST CDS_LIB mstr_standard
J 0
(-2200 4050);
PAINT ORANGE (-2200 4050);
DISPLAY INVISIBLE (-2200 4050);
FORCEPROP 1 LAST OFFPAGE TRUE
J 0
(-1875 3925);
DISPLAY 1.404255 (-1875 3925);
PAINT GREEN (-1875 3925);
DISPLAY INVISIBLE (-1875 3925);
FORCEPROP 1 LAST COMMENT_BODY TRUE
J 0
(-2075 3950);
DISPLAY 1.404255 (-2075 3950);
PAINT PEACH (-2075 3950);
DISPLAY INVISIBLE (-2075 3950);
FORCEPROP 2 LAST PATH I52
J 0
(-2450 4100);
DISPLAY 1.021277 (-2450 4100);
PAINT ORANGE (-2450 4100);
DISPLAY INVISIBLE (-2450 4100);
FORCEADD OFFPAGE..1
(-2200 4000);
FORCEPROP 2 LAST $XR1 96 
J 0
(-2542 4000);
DISPLAY 0.638298 (-2542 4000);
PAINT MONO (-2542 4000);
FORCEPROP 2 LAST $XR0 190 
J 0
(-2452 4000);
DISPLAY 0.638298 (-2452 4000);
PAINT MONO (-2452 4000);
FORCEPROP 2 LAST CDS_LIB mstr_standard
J 0
(-2200 4000);
PAINT ORANGE (-2200 4000);
DISPLAY INVISIBLE (-2200 4000);
FORCEPROP 1 LAST OFFPAGE TRUE
J 0
(-1875 3875);
DISPLAY 1.404255 (-1875 3875);
PAINT GREEN (-1875 3875);
DISPLAY INVISIBLE (-1875 3875);
FORCEPROP 1 LAST COMMENT_BODY TRUE
J 0
(-2075 3900);
DISPLAY 1.404255 (-2075 3900);
PAINT PEACH (-2075 3900);
DISPLAY INVISIBLE (-2075 3900);
FORCEPROP 2 LAST PATH I53
J 0
(-2450 4050);
DISPLAY 1.021277 (-2450 4050);
PAINT ORANGE (-2450 4050);
DISPLAY INVISIBLE (-2450 4050);
FORCEADD RES..2
(-2100 2350);
FORCEPROP 1 LAST LOCATION R4C8
J 0
(-2055 2475);
DISPLAY 0.617021 (-2055 2475);
PAINT AQUA (-2055 2475);
FORCEPROP 1 LAST PART_NUMBER G21796-026
J 0
(-2060 2225);
DISPLAY 0.617021 (-2060 2225);
PAINT BLUE (-2060 2225);
FORCEPROP 1 LAST VALUE 1.00K
J 0
(-2055 2425);
DISPLAY 0.617021 (-2055 2425);
PAINT SKYBLUE (-2055 2425);
FORCEPROP 1 LAST TOLERANCE 1%
J 0
(-2055 2375);
DISPLAY 0.617021 (-2055 2375);
PAINT SKYBLUE (-2055 2375);
FORCEPROP 1 LAST PACK_TYPE 0402
J 0
(-2060 2175);
DISPLAY 0.617021 (-2060 2175);
PAINT SKYBLUE (-2060 2175);
FORCEPROP 1 LAST MATERIAL CHIP
J 0
(-2060 2275);
DISPLAY 0.617021 (-2060 2275);
PAINT SKYBLUE (-2060 2275);
FORCEPROP 1 LAST WATTAGE 1/16W
J 0
(-2060 2325);
DISPLAY 0.617021 (-2060 2325);
PAINT SKYBLUE (-2060 2325);
FORCEPROP 1 LASTPIN (-2100 2250) $PN 2
J 0
(-2095 2260);
DISPLAY 0.617021 (-2095 2260);
PAINT WHITE (-2095 2260);
FORCEPROP 1 LASTPIN (-2100 2450) $PN 1
J 0
(-2095 2412);
DISPLAY 0.617021 (-2095 2412);
PAINT WHITE (-2095 2412);
FORCEPROP 2 LAST BOM_COST PROC_SIDEBAND
J 0
(-2100 2350);
DISPLAY 1.617021 (-2100 2350);
PAINT WHITE (-2100 2350);
DISPLAY INVISIBLE (-2100 2350);
FORCEPROP 2 LAST CDS_LIB mstr_discrete
J 0
(-2100 2350);
DISPLAY 1.617021 (-2100 2350);
PAINT ORANGE (-2100 2350);
DISPLAY INVISIBLE (-2100 2350);
FORCEPROP 2 LAST CDS_SEC 1
J 0
(-2050 2575);
DISPLAY 2.276596 (-2050 2575);
PAINT ORANGE (-2050 2575);
DISPLAY INVISIBLE (-2050 2575);
FORCEPROP 2 LAST $SEC 1
J 0
(-2050 2575);
DISPLAY 1.510638 (-2050 2575);
PAINT MONO (-2050 2575);
DISPLAY INVISIBLE (-2050 2575);
FORCEPROP 2 LAST CDS_LOCATION R4C8
J 0
(-2055 2475);
DISPLAY 0.617021 (-2055 2475);
PAINT AQUA (-2055 2475);
DISPLAY INVISIBLE (-2055 2475);
FORCEPROP 1 LAST PATH I55
J 0
(-2050 2525);
DISPLAY 0.978723 (-2050 2525);
PAINT WHITE (-2050 2525);
DISPLAY INVISIBLE (-2050 2525);
FORCEPROP 2 LAST ROOM PROC_RSTS_PGOODS
J 0
(-2075 2125);
DISPLAY 1.617021 (-2075 2125);
PAINT WHITE (-2075 2125);
DISPLAY INVISIBLE (-2075 2125);
FORCEADD OFFPAGE..1
(-2200 1800);
FORCEPROP 2 LAST $XR0 190 
J 0
(-2452 1800);
DISPLAY 0.638298 (-2452 1800);
PAINT MONO (-2452 1800);
FORCEPROP 2 LAST CDS_LIB mstr_standard
J 0
(-2200 1800);
PAINT ORANGE (-2200 1800);
DISPLAY INVISIBLE (-2200 1800);
FORCEPROP 1 LAST OFFPAGE TRUE
J 0
(-1875 1675);
DISPLAY 1.404255 (-1875 1675);
PAINT GREEN (-1875 1675);
DISPLAY INVISIBLE (-1875 1675);
FORCEPROP 1 LAST COMMENT_BODY TRUE
J 0
(-2075 1700);
DISPLAY 1.404255 (-2075 1700);
PAINT PEACH (-2075 1700);
DISPLAY INVISIBLE (-2075 1700);
FORCEPROP 2 LAST PATH I59
J 0
(-2450 1850);
DISPLAY 1.021277 (-2450 1850);
PAINT ORANGE (-2450 1850);
DISPLAY INVISIBLE (-2450 1850);
FORCEADD PVDDQ_ABC..1
(575 4700);
FORCEPROP 3 LASTPIN (575 4650) SIG_NAME PVDDQ_ABC\g
J 0
(585 4660);
DISPLAY 0.659574 (585 4660);
PAINT MONO (585 4660);
DISPLAY INVISIBLE (585 4660);
FORCEPROP 1 LAST VOLTAGE 1.2V
J 0
(530 4657);
DISPLAY 0.340426 (530 4657);
PAINT SKYBLUE (530 4657);
DISPLAY INVISIBLE (530 4657);
FORCEPROP 2 LAST CDS_LIB mstr_symbols
J 0
(575 4700);
PAINT ORANGE (575 4700);
DISPLAY INVISIBLE (575 4700);
FORCEPROP 1 LAST BODY_TYPE PLUMBING
J 0
(530 4657);
DISPLAY 0.340426 (530 4657);
PAINT GREEN (530 4657);
DISPLAY INVISIBLE (530 4657);
FORCEPROP 1 LAST PATH I6
J 0
(625 4725);
DISPLAY 0.872340 (625 4725);
PAINT AQUA (625 4725);
DISPLAY INVISIBLE (625 4725);
FORCEPROP 1 LAST HDL_POWER PVDDQ_ABC
J 1
(575 4750);
DISPLAY 0.872340 (575 4750);
PAINT GREEN (575 4750);
DISPLAY INVISIBLE (575 4750);
FORCEADD OFFPAGE..1
(-2200 1700);
FORCEPROP 2 LAST $XR1 96 
J 0
(-2542 1700);
DISPLAY 0.638298 (-2542 1700);
PAINT MONO (-2542 1700);
FORCEPROP 2 LAST $XR0 190 
J 0
(-2452 1700);
DISPLAY 0.638298 (-2452 1700);
PAINT MONO (-2452 1700);
FORCEPROP 2 LAST CDS_LIB mstr_standard
J 0
(-2200 1700);
PAINT ORANGE (-2200 1700);
DISPLAY INVISIBLE (-2200 1700);
FORCEPROP 1 LAST OFFPAGE TRUE
J 0
(-1875 1575);
DISPLAY 1.404255 (-1875 1575);
PAINT GREEN (-1875 1575);
DISPLAY INVISIBLE (-1875 1575);
FORCEPROP 1 LAST COMMENT_BODY TRUE
J 0
(-2075 1600);
DISPLAY 1.404255 (-2075 1600);
PAINT PEACH (-2075 1600);
DISPLAY INVISIBLE (-2075 1600);
FORCEPROP 2 LAST PATH I60
J 0
(-2450 1750);
DISPLAY 1.021277 (-2450 1750);
PAINT ORANGE (-2450 1750);
DISPLAY INVISIBLE (-2450 1750);
FORCEADD OFFPAGE..1
(-2200 1750);
FORCEPROP 2 LAST $XR0 190 
J 0
(-2452 1750);
DISPLAY 0.638298 (-2452 1750);
PAINT MONO (-2452 1750);
FORCEPROP 2 LAST CDS_LIB mstr_standard
J 0
(-2200 1750);
PAINT ORANGE (-2200 1750);
DISPLAY INVISIBLE (-2200 1750);
FORCEPROP 1 LAST OFFPAGE TRUE
J 0
(-1875 1625);
DISPLAY 1.404255 (-1875 1625);
PAINT GREEN (-1875 1625);
DISPLAY INVISIBLE (-1875 1625);
FORCEPROP 1 LAST COMMENT_BODY TRUE
J 0
(-2075 1650);
DISPLAY 1.404255 (-2075 1650);
PAINT PEACH (-2075 1650);
DISPLAY INVISIBLE (-2075 1650);
FORCEPROP 2 LAST PATH I61
J 0
(-2450 1800);
DISPLAY 1.021277 (-2450 1800);
PAINT ORANGE (-2450 1800);
DISPLAY INVISIBLE (-2450 1800);
FORCEADD P3V3_STBY..1
(-2100 2725);
FORCEPROP 3 LASTPIN (-2100 2675) SIG_NAME P3V3_STBY\g
J 0
(-2090 2685);
DISPLAY 0.659574 (-2090 2685);
PAINT MONO (-2090 2685);
DISPLAY INVISIBLE (-2090 2685);
FORCEPROP 1 LAST VOLTAGE 3.3V
J 0
(-2145 2682);
DISPLAY 0.340426 (-2145 2682);
PAINT SKYBLUE (-2145 2682);
DISPLAY INVISIBLE (-2145 2682);
FORCEPROP 2 LAST CDS_LIB mstr_symbols
J 0
(-2100 2725);
PAINT ORANGE (-2100 2725);
DISPLAY INVISIBLE (-2100 2725);
FORCEPROP 1 LAST SIZE 1B
J 0
(-2055 2747);
DISPLAY 0.340426 (-2055 2747);
PAINT GREEN (-2055 2747);
DISPLAY INVISIBLE (-2055 2747);
FORCEPROP 1 LAST BODY_TYPE PLUMBING
J 0
(-2145 2682);
DISPLAY 0.340426 (-2145 2682);
PAINT GREEN (-2145 2682);
DISPLAY INVISIBLE (-2145 2682);
FORCEPROP 1 LAST PATH I65
J 0
(-2055 2727);
DISPLAY 0.340426 (-2055 2727);
PAINT GREEN (-2055 2727);
DISPLAY INVISIBLE (-2055 2727);
FORCEPROP 1 LAST HDL_POWER P3V3_STBY
J 0
(-2400 2600);
DISPLAY 0.872340 (-2400 2600);
PAINT ORANGE (-2400 2600);
DISPLAY INVISIBLE (-2400 2600);
FORCEADD P3V3_STBY..1
(-2100 5050);
FORCEPROP 3 LASTPIN (-2100 5000) SIG_NAME P3V3_STBY\g
J 0
(-2090 5010);
DISPLAY 0.659574 (-2090 5010);
PAINT MONO (-2090 5010);
DISPLAY INVISIBLE (-2090 5010);
FORCEPROP 1 LAST VOLTAGE 3.3V
J 0
(-2145 5007);
DISPLAY 0.340426 (-2145 5007);
PAINT SKYBLUE (-2145 5007);
DISPLAY INVISIBLE (-2145 5007);
FORCEPROP 1 LAST SIZE 1B
J 0
(-2055 5072);
DISPLAY 0.340426 (-2055 5072);
PAINT GREEN (-2055 5072);
DISPLAY INVISIBLE (-2055 5072);
FORCEPROP 2 LAST CDS_LIB mstr_symbols
J 0
(-2100 5050);
PAINT ORANGE (-2100 5050);
DISPLAY INVISIBLE (-2100 5050);
FORCEPROP 1 LAST BODY_TYPE PLUMBING
J 0
(-2145 5007);
DISPLAY 0.340426 (-2145 5007);
PAINT GREEN (-2145 5007);
DISPLAY INVISIBLE (-2145 5007);
FORCEPROP 1 LAST PATH I68
J 0
(-2055 5052);
DISPLAY 0.340426 (-2055 5052);
PAINT GREEN (-2055 5052);
DISPLAY INVISIBLE (-2055 5052);
FORCEPROP 1 LAST HDL_POWER P3V3_STBY
J 0
(-2400 4925);
DISPLAY 0.872340 (-2400 4925);
PAINT ORANGE (-2400 4925);
DISPLAY INVISIBLE (-2400 4925);
FORCEADD RES..1
(-2400 2050);
FORCEPROP 1 LAST LOCATION R4C9
J 0
(-2450 2100);
DISPLAY 0.617021 (-2450 2100);
PAINT AQUA (-2450 2100);
FORCEPROP 1 LAST PART_NUMBER G21796-026
J 0
(-2450 2150);
DISPLAY 0.617021 (-2450 2150);
PAINT BLUE (-2450 2150);
FORCEPROP 1 LAST VALUE 1.00K
J 2
(-2425 1950);
DISPLAY 0.617021 (-2425 1950);
PAINT SKYBLUE (-2425 1950);
FORCEPROP 1 LAST TOLERANCE 1%
J 0
(-2400 1950);
DISPLAY 0.617021 (-2400 1950);
PAINT SKYBLUE (-2400 1950);
FORCEPROP 1 LAST PACK_TYPE 0402
J 0
(-2150 1900);
DISPLAY 0.617021 (-2150 1900);
PAINT SKYBLUE (-2150 1900);
FORCEPROP 1 LAST MATERIAL CHIP
J 0
(-2400 1900);
DISPLAY 0.617021 (-2400 1900);
PAINT SKYBLUE (-2400 1900);
FORCEPROP 1 LAST WATTAGE 1/16W
J 2
(-2425 1900);
DISPLAY 0.617021 (-2425 1900);
PAINT SKYBLUE (-2425 1900);
FORCEPROP 1 LASTPIN (-2300 2050) $PN 2
J 0
(-2338 2062);
DISPLAY 0.617021 (-2338 2062);
PAINT ORANGE (-2338 2062);
FORCEPROP 1 LASTPIN (-2500 2050) $PN 1
J 0
(-2488 2062);
DISPLAY 0.617021 (-2488 2062);
PAINT ORANGE (-2488 2062);
FORCEPROP 0 LAST BOM_COST PROC_SIDEBAND
J 0
(-2450 2350);
DISPLAY 1.021277 (-2450 2350);
PAINT ORANGE (-2450 2350);
DISPLAY INVISIBLE (-2450 2350);
FORCEPROP 2 LAST SEC_TYPE 0402
J 0
(-2450 2250);
DISPLAY 1.021277 (-2450 2250);
PAINT ORANGE (-2450 2250);
DISPLAY INVISIBLE (-2450 2250);
FORCEPROP 2 LAST CDS_LIB mstr_discrete
J 0
(-2400 2050);
PAINT ORANGE (-2400 2050);
DISPLAY INVISIBLE (-2400 2050);
FORCEPROP 2 LAST SEC 1
J 0
(-2450 2250);
DISPLAY 0.680851 (-2450 2250);
PAINT MONO (-2450 2250);
DISPLAY INVISIBLE (-2450 2250);
FORCEPROP 2 LAST CDS_LOCATION R4C9
J 0
(-2450 2100);
DISPLAY 0.617021 (-2450 2100);
PAINT AQUA (-2450 2100);
DISPLAY INVISIBLE (-2450 2100);
FORCEPROP 1 LAST PATH I69
J 0
(-2450 2200);
DISPLAY 0.978723 (-2450 2200);
PAINT WHITE (-2450 2200);
DISPLAY INVISIBLE (-2450 2200);
FORCEPROP 2 LAST ROOM PROC_RSTS_PGOODS
J 0
(-2450 2250);
DISPLAY 1.021277 (-2450 2250);
PAINT ORANGE (-2450 2250);
DISPLAY INVISIBLE (-2450 2250);
FORCEADD RES..2
(575 4450);
FORCEPROP 1 LAST LOCATION R3P38
J 0
(620 4575);
DISPLAY 0.617021 (620 4575);
PAINT AQUA (620 4575);
FORCEPROP 1 LAST PART_NUMBER G21796-298
J 0
(615 4325);
DISPLAY 0.617021 (615 4325);
PAINT BLUE (615 4325);
FORCEPROP 1 LAST VALUE 64.9
J 0
(620 4525);
DISPLAY 0.617021 (620 4525);
PAINT SKYBLUE (620 4525);
FORCEPROP 1 LAST TOLERANCE 1.0%
J 0
(620 4475);
DISPLAY 0.617021 (620 4475);
PAINT SKYBLUE (620 4475);
FORCEPROP 1 LAST PACK_TYPE 0402
J 0
(615 4275);
DISPLAY 0.617021 (615 4275);
PAINT SKYBLUE (615 4275);
FORCEPROP 1 LAST MATERIAL CHIP
J 0
(615 4375);
DISPLAY 0.617021 (615 4375);
PAINT SKYBLUE (615 4375);
FORCEPROP 1 LAST WATTAGE 1/16W
J 0
(615 4425);
DISPLAY 0.617021 (615 4425);
PAINT SKYBLUE (615 4425);
FORCEPROP 1 LASTPIN (575 4350) $PN 2
J 0
(580 4360);
DISPLAY 0.617021 (580 4360);
PAINT WHITE (580 4360);
FORCEPROP 1 LASTPIN (575 4550) $PN 1
J 0
(580 4512);
DISPLAY 0.617021 (580 4512);
PAINT WHITE (580 4512);
FORCEPROP 2 LAST BOM_COST PROC_SIDEBAND
J 0
(625 4625);
DISPLAY 1.659574 (625 4625);
PAINT WHITE (625 4625);
DISPLAY INVISIBLE (625 4625);
FORCEPROP 2 LAST CDS_LIB mstr_discrete
J 0
(575 4450);
DISPLAY 1.617021 (575 4450);
PAINT ORANGE (575 4450);
DISPLAY INVISIBLE (575 4450);
FORCEPROP 2 LAST CDS_SEC 1
J 0
(625 4675);
DISPLAY 2.276596 (625 4675);
PAINT ORANGE (625 4675);
DISPLAY INVISIBLE (625 4675);
FORCEPROP 2 LAST $SEC 1
J 0
(625 4675);
DISPLAY 1.510638 (625 4675);
PAINT MONO (625 4675);
DISPLAY INVISIBLE (625 4675);
FORCEPROP 2 LAST CDS_LOCATION R3P38
J 0
(620 4575);
DISPLAY 0.617021 (620 4575);
PAINT AQUA (620 4575);
DISPLAY INVISIBLE (620 4575);
FORCEPROP 1 LAST PATH I7
J 0
(625 4625);
DISPLAY 0.978723 (625 4625);
PAINT WHITE (625 4625);
DISPLAY INVISIBLE (625 4625);
FORCEPROP 2 LAST ROOM PROC_RSTS_PGOODS
J 0
(625 4625);
DISPLAY 2.276596 (625 4625);
PAINT WHITE (625 4625);
DISPLAY INVISIBLE (625 4625);
FORCEADD GND..1
(-2875 1950);
FORCEPROP 3 LASTPIN (-2875 2000) SIG_NAME GND\g
J 0
(-2865 2010);
DISPLAY 0.659574 (-2865 2010);
PAINT MONO (-2865 2010);
DISPLAY INVISIBLE (-2865 2010);
FORCEPROP 1 LAST VOLTAGE 0.0V
J 0
(-2920 1907);
DISPLAY 0.340426 (-2920 1907);
PAINT SKYBLUE (-2920 1907);
DISPLAY INVISIBLE (-2920 1907);
FORCEPROP 2 LAST CDS_LIB mstr_symbols
J 0
(-2875 1950);
PAINT ORANGE (-2875 1950);
DISPLAY INVISIBLE (-2875 1950);
FORCEPROP 1 LAST SIZE 1B
J 0
(-2800 1900);
DISPLAY 1.893617 (-2800 1900);
PAINT GREEN (-2800 1900);
DISPLAY INVISIBLE (-2800 1900);
FORCEPROP 1 LAST BODY_TYPE PLUMBING
J 0
(-2920 1907);
DISPLAY 0.340426 (-2920 1907);
PAINT GREEN (-2920 1907);
DISPLAY INVISIBLE (-2920 1907);
FORCEPROP 1 LAST PATH I70
J 0
(-2800 1950);
DISPLAY 0.872340 (-2800 1950);
PAINT AQUA (-2800 1950);
DISPLAY INVISIBLE (-2800 1950);
FORCEPROP 1 LAST HDL_POWER GND
J 0
(-2875 2100);
DISPLAY 1.595745 (-2875 2100);
PAINT GREEN (-2875 2100);
DISPLAY INVISIBLE (-2875 2100);
FORCEADD RES..1
(-2400 4350);
FORCEPROP 1 LAST LOCATION R3P32
J 0
(-2450 4400);
DISPLAY 0.617021 (-2450 4400);
PAINT AQUA (-2450 4400);
FORCEPROP 1 LAST VALUE 1.00K
J 2
(-2425 4250);
DISPLAY 0.617021 (-2425 4250);
PAINT SKYBLUE (-2425 4250);
FORCEPROP 1 LAST TOLERANCE 1%
J 0
(-2400 4250);
DISPLAY 0.617021 (-2400 4250);
PAINT SKYBLUE (-2400 4250);
FORCEPROP 1 LAST PACK_TYPE 0402
J 0
(-2650 4225);
DISPLAY 0.617021 (-2650 4225);
PAINT SKYBLUE (-2650 4225);
FORCEPROP 1 LAST MATERIAL CHIP
J 0
(-2400 4200);
DISPLAY 0.617021 (-2400 4200);
PAINT SKYBLUE (-2400 4200);
FORCEPROP 1 LAST WATTAGE 1/16W
J 2
(-2425 4200);
DISPLAY 0.617021 (-2425 4200);
PAINT SKYBLUE (-2425 4200);
FORCEPROP 1 LASTPIN (-2300 4350) $PN 2
J 0
(-2338 4362);
DISPLAY 0.617021 (-2338 4362);
PAINT ORANGE (-2338 4362);
FORCEPROP 1 LASTPIN (-2500 4350) $PN 1
J 0
(-2488 4362);
DISPLAY 0.617021 (-2488 4362);
PAINT ORANGE (-2488 4362);
FORCEPROP 1 LAST PART_NUMBER G21796-026
J 0
(-2450 4450);
DISPLAY 0.617021 (-2450 4450);
PAINT BLUE (-2450 4450);
FORCEPROP 0 LAST BOM_COST PROC_SIDEBAND
J 0
(-2450 4650);
DISPLAY 1.021277 (-2450 4650);
PAINT ORANGE (-2450 4650);
DISPLAY INVISIBLE (-2450 4650);
FORCEPROP 2 LAST SEC_TYPE 0402
J 0
(-2450 4550);
DISPLAY 1.021277 (-2450 4550);
PAINT ORANGE (-2450 4550);
DISPLAY INVISIBLE (-2450 4550);
FORCEPROP 2 LAST CDS_LIB mstr_discrete
J 0
(-2400 4350);
PAINT ORANGE (-2400 4350);
DISPLAY INVISIBLE (-2400 4350);
FORCEPROP 2 LAST SEC 1
J 0
(-2450 4550);
DISPLAY 0.680851 (-2450 4550);
PAINT MONO (-2450 4550);
DISPLAY INVISIBLE (-2450 4550);
FORCEPROP 2 LAST CDS_LOCATION R3P32
J 0
(-2450 4400);
DISPLAY 0.617021 (-2450 4400);
PAINT AQUA (-2450 4400);
DISPLAY INVISIBLE (-2450 4400);
FORCEPROP 1 LAST PATH I71
J 0
(-2450 4500);
DISPLAY 0.978723 (-2450 4500);
PAINT WHITE (-2450 4500);
DISPLAY INVISIBLE (-2450 4500);
FORCEPROP 2 LAST ROOM PROC_RSTS_PGOODS
J 0
(-2450 4550);
DISPLAY 1.021277 (-2450 4550);
PAINT ORANGE (-2450 4550);
DISPLAY INVISIBLE (-2450 4550);
FORCEADD GND..1
(-2775 4225);
FORCEPROP 3 LASTPIN (-2775 4275) SIG_NAME GND\g
J 0
(-2765 4285);
DISPLAY 0.659574 (-2765 4285);
PAINT MONO (-2765 4285);
DISPLAY INVISIBLE (-2765 4285);
FORCEPROP 1 LAST VOLTAGE 0.0V
J 0
(-2820 4182);
DISPLAY 0.340426 (-2820 4182);
PAINT SKYBLUE (-2820 4182);
DISPLAY INVISIBLE (-2820 4182);
FORCEPROP 1 LAST SIZE 1B
J 0
(-2700 4175);
DISPLAY 1.893617 (-2700 4175);
PAINT GREEN (-2700 4175);
DISPLAY INVISIBLE (-2700 4175);
FORCEPROP 2 LAST CDS_LIB mstr_symbols
J 0
(-2775 4225);
PAINT ORANGE (-2775 4225);
DISPLAY INVISIBLE (-2775 4225);
FORCEPROP 1 LAST BODY_TYPE PLUMBING
J 0
(-2820 4182);
DISPLAY 0.340426 (-2820 4182);
PAINT GREEN (-2820 4182);
DISPLAY INVISIBLE (-2820 4182);
FORCEPROP 1 LAST PATH I72
J 0
(-2700 4225);
DISPLAY 0.872340 (-2700 4225);
PAINT AQUA (-2700 4225);
DISPLAY INVISIBLE (-2700 4225);
FORCEPROP 1 LAST HDL_POWER GND
J 0
(-2775 4375);
DISPLAY 1.595745 (-2775 4375);
PAINT GREEN (-2775 4375);
DISPLAY INVISIBLE (-2775 4375);
FORCEADD CAP_A..1
(-1650 4650);
FORCEPROP 1 LAST LOCATION C3P42
J 0
(-1600 4750);
DISPLAY 0.617021 (-1600 4750);
PAINT AQUA (-1600 4750);
FORCEPROP 1 LAST PART_NUMBER D97712-004
J 0
(-1600 4500);
DISPLAY 0.617021 (-1600 4500);
PAINT BLUE (-1600 4500);
FORCEPROP 1 LAST VALUE 1.0UF
J 0
(-1600 4700);
DISPLAY 0.617021 (-1600 4700);
PAINT SKYBLUE (-1600 4700);
FORCEPROP 1 LAST TOLERANCE 10%
J 0
(-1600 4600);
DISPLAY 0.617021 (-1600 4600);
PAINT SKYBLUE (-1600 4600);
FORCEPROP 1 LAST PACK_TYPE 0402V
J 0
(-1600 4450);
DISPLAY 0.617021 (-1600 4450);
PAINT SKYBLUE (-1600 4450);
FORCEPROP 1 LAST VOLTAGE 6.3V
J 0
(-1600 4650);
DISPLAY 0.617021 (-1600 4650);
PAINT SKYBLUE (-1600 4650);
FORCEPROP 1 LAST MATERIAL X6S
J 0
(-1600 4550);
DISPLAY 0.617021 (-1600 4550);
PAINT SKYBLUE (-1600 4550);
FORCEPROP 1 LASTPIN (-1650 4750) $PN 1
J 0
(-1640 4730);
DISPLAY 0.617021 (-1640 4730);
PAINT WHITE (-1640 4730);
FORCEPROP 1 LASTPIN (-1650 4550) $PN 2
J 0
(-1640 4530);
DISPLAY 0.617021 (-1640 4530);
PAINT WHITE (-1640 4530);
FORCEPROP 2 LAST CDS_LOCATION C3P42
J 0
(-1600 4750);
DISPLAY 0.617021 (-1600 4750);
PAINT AQUA (-1600 4750);
DISPLAY INVISIBLE (-1600 4750);
FORCEPROP 2 LAST BOM_COST PROC_SIDEBAND
J 0
(-1650 4650);
DISPLAY 1.617021 (-1650 4650);
PAINT WHITE (-1650 4650);
DISPLAY INVISIBLE (-1650 4650);
FORCEPROP 2 LAST CDS_LIB dev_discrete
J 0
(-1650 4650);
PAINT ORANGE (-1650 4650);
DISPLAY INVISIBLE (-1650 4650);
FORCEPROP 2 LAST CDS_SEC 1
J 0
(-1600 4800);
PAINT ORANGE (-1600 4800);
DISPLAY INVISIBLE (-1600 4800);
FORCEPROP 2 LAST SEC_TYPE 0402V
J 0
(-1600 4850);
DISPLAY 1.617021 (-1600 4850);
PAINT MONO (-1600 4850);
DISPLAY INVISIBLE (-1600 4850);
FORCEPROP 2 LAST SEC 1
J 0
(-1600 4850);
DISPLAY 1.510638 (-1600 4850);
PAINT MONO (-1600 4850);
DISPLAY INVISIBLE (-1600 4850);
FORCEPROP 1 LAST PATH I73
J 0
(-1600 4800);
DISPLAY 0.978723 (-1600 4800);
PAINT WHITE (-1600 4800);
DISPLAY INVISIBLE (-1600 4800);
FORCEPROP 2 LAST ROOM PROC_RSTS_PGOODS
J 0
(-1600 4400);
DISPLAY 1.617021 (-1600 4400);
PAINT WHITE (-1600 4400);
DISPLAY INVISIBLE (-1600 4400);
FORCEADD GND..1
(-1650 4450);
FORCEPROP 3 LASTPIN (-1650 4500) SIG_NAME GND\g
J 0
(-1640 4510);
DISPLAY 0.659574 (-1640 4510);
PAINT MONO (-1640 4510);
DISPLAY INVISIBLE (-1640 4510);
FORCEPROP 1 LAST VOLTAGE 0.0V
J 0
(-1695 4407);
DISPLAY 0.340426 (-1695 4407);
PAINT SKYBLUE (-1695 4407);
DISPLAY INVISIBLE (-1695 4407);
FORCEPROP 2 LAST CDS_LIB mstr_symbols
J 0
(-1650 4450);
DISPLAY 2.212766 (-1650 4450);
PAINT ORANGE (-1650 4450);
DISPLAY INVISIBLE (-1650 4450);
FORCEPROP 1 LAST SIZE 1B
J 0
(-1575 4400);
DISPLAY 1.893617 (-1575 4400);
PAINT GREEN (-1575 4400);
DISPLAY INVISIBLE (-1575 4400);
FORCEPROP 1 LAST BODY_TYPE PLUMBING
J 0
(-1695 4407);
DISPLAY 0.340426 (-1695 4407);
PAINT GREEN (-1695 4407);
DISPLAY INVISIBLE (-1695 4407);
FORCEPROP 1 LAST PATH I74
J 0
(-1575 4450);
DISPLAY 0.872340 (-1575 4450);
PAINT AQUA (-1575 4450);
DISPLAY INVISIBLE (-1575 4450);
FORCEPROP 1 LAST HDL_POWER GND
J 0
(-1650 4600);
DISPLAY 1.595745 (-1650 4600);
PAINT GREEN (-1650 4600);
DISPLAY INVISIBLE (-1650 4600);
FORCEADD CAP_A..1
(-1725 2325);
FORCEPROP 1 LAST LOCATION C4C3
J 0
(-1675 2425);
DISPLAY 0.617021 (-1675 2425);
PAINT AQUA (-1675 2425);
FORCEPROP 1 LAST PART_NUMBER D97712-004
J 0
(-1675 2175);
DISPLAY 0.617021 (-1675 2175);
PAINT BLUE (-1675 2175);
FORCEPROP 1 LAST VALUE 1.0UF
J 0
(-1675 2375);
DISPLAY 0.617021 (-1675 2375);
PAINT SKYBLUE (-1675 2375);
FORCEPROP 1 LAST TOLERANCE 10%
J 0
(-1675 2275);
DISPLAY 0.617021 (-1675 2275);
PAINT SKYBLUE (-1675 2275);
FORCEPROP 1 LAST PACK_TYPE 0402V
J 0
(-1675 2125);
DISPLAY 0.617021 (-1675 2125);
PAINT SKYBLUE (-1675 2125);
FORCEPROP 1 LAST VOLTAGE 6.3V
J 0
(-1675 2325);
DISPLAY 0.617021 (-1675 2325);
PAINT SKYBLUE (-1675 2325);
FORCEPROP 1 LAST MATERIAL X6S
J 0
(-1675 2225);
DISPLAY 0.617021 (-1675 2225);
PAINT SKYBLUE (-1675 2225);
FORCEPROP 1 LASTPIN (-1725 2425) $PN 1
J 0
(-1715 2405);
DISPLAY 0.617021 (-1715 2405);
PAINT WHITE (-1715 2405);
FORCEPROP 1 LASTPIN (-1725 2225) $PN 2
J 0
(-1715 2205);
DISPLAY 0.617021 (-1715 2205);
PAINT WHITE (-1715 2205);
FORCEPROP 2 LAST CDS_LOCATION C4C3
J 0
(-1675 2425);
DISPLAY 0.617021 (-1675 2425);
PAINT AQUA (-1675 2425);
DISPLAY INVISIBLE (-1675 2425);
FORCEPROP 2 LAST BOM_COST PROC_SIDEBAND
J 0
(-1725 2325);
DISPLAY 1.617021 (-1725 2325);
PAINT WHITE (-1725 2325);
DISPLAY INVISIBLE (-1725 2325);
FORCEPROP 2 LAST CDS_LIB dev_discrete
J 0
(-1725 2325);
PAINT ORANGE (-1725 2325);
DISPLAY INVISIBLE (-1725 2325);
FORCEPROP 2 LAST CDS_SEC 1
J 0
(-1675 2475);
PAINT ORANGE (-1675 2475);
DISPLAY INVISIBLE (-1675 2475);
FORCEPROP 2 LAST SEC_TYPE 0402V
J 0
(-1675 2525);
DISPLAY 1.617021 (-1675 2525);
PAINT MONO (-1675 2525);
DISPLAY INVISIBLE (-1675 2525);
FORCEPROP 2 LAST SEC 1
J 0
(-1675 2525);
DISPLAY 1.510638 (-1675 2525);
PAINT MONO (-1675 2525);
DISPLAY INVISIBLE (-1675 2525);
FORCEPROP 1 LAST PATH I75
J 0
(-1675 2475);
DISPLAY 0.978723 (-1675 2475);
PAINT WHITE (-1675 2475);
DISPLAY INVISIBLE (-1675 2475);
FORCEPROP 2 LAST ROOM PROC_RSTS_PGOODS
J 0
(-1675 2075);
DISPLAY 1.617021 (-1675 2075);
PAINT WHITE (-1675 2075);
DISPLAY INVISIBLE (-1675 2075);
FORCEADD GND..1
(-1725 2125);
FORCEPROP 3 LASTPIN (-1725 2175) SIG_NAME GND\g
J 0
(-1715 2185);
DISPLAY 0.659574 (-1715 2185);
PAINT MONO (-1715 2185);
DISPLAY INVISIBLE (-1715 2185);
FORCEPROP 1 LAST VOLTAGE 0.0V
J 0
(-1770 2082);
DISPLAY 0.340426 (-1770 2082);
PAINT SKYBLUE (-1770 2082);
DISPLAY INVISIBLE (-1770 2082);
FORCEPROP 2 LAST CDS_LIB mstr_symbols
J 0
(-1725 2125);
DISPLAY 2.212766 (-1725 2125);
PAINT ORANGE (-1725 2125);
DISPLAY INVISIBLE (-1725 2125);
FORCEPROP 1 LAST SIZE 1B
J 0
(-1650 2075);
DISPLAY 1.893617 (-1650 2075);
PAINT GREEN (-1650 2075);
DISPLAY INVISIBLE (-1650 2075);
FORCEPROP 1 LAST BODY_TYPE PLUMBING
J 0
(-1770 2082);
DISPLAY 0.340426 (-1770 2082);
PAINT GREEN (-1770 2082);
DISPLAY INVISIBLE (-1770 2082);
FORCEPROP 1 LAST PATH I76
J 0
(-1650 2125);
DISPLAY 0.872340 (-1650 2125);
PAINT AQUA (-1650 2125);
DISPLAY INVISIBLE (-1650 2125);
FORCEPROP 1 LAST HDL_POWER GND
J 0
(-1725 2275);
DISPLAY 1.595745 (-1725 2275);
PAINT GREEN (-1725 2275);
DISPLAY INVISIBLE (-1725 2275);
FORCEADD OFFPAGE..2
(3375 4100);
FORCEPROP 2 LAST $XR1 113 
J 0
(3654 4100);
DISPLAY 0.638298 (3654 4100);
PAINT MONO (3654 4100);
FORCEPROP 2 LAST $XR0 21 
J 0
(3564 4100);
DISPLAY 0.638298 (3564 4100);
PAINT MONO (3564 4100);
FORCEPROP 2 LAST CDS_LIB mstr_standard
J 0
(3375 4100);
PAINT ORANGE (3375 4100);
DISPLAY INVISIBLE (3375 4100);
FORCEPROP 1 LAST OFFPAGE TRUE
J 0
(3700 3975);
DISPLAY 1.404255 (3700 3975);
PAINT GREEN (3700 3975);
DISPLAY INVISIBLE (3700 3975);
FORCEPROP 1 LAST COMMENT_BODY TRUE
J 0
(3330 4005);
DISPLAY 1.404255 (3330 4005);
PAINT PEACH (3330 4005);
DISPLAY INVISIBLE (3330 4005);
FORCEPROP 2 LAST PATH I8
J 0
(3625 4150);
DISPLAY 1.021277 (3625 4150);
PAINT ORANGE (3625 4150);
DISPLAY INVISIBLE (3625 4150);
FORCEADD OFFPAGE..2
(3375 3875);
FORCEPROP 2 LAST $XR0 21 
J 0
(3564 3875);
DISPLAY 0.638298 (3564 3875);
PAINT MONO (3564 3875);
FORCEPROP 2 LAST CDS_LIB mstr_standard
J 0
(3375 3875);
PAINT ORANGE (3375 3875);
DISPLAY INVISIBLE (3375 3875);
FORCEPROP 1 LAST OFFPAGE TRUE
J 0
(3700 3750);
DISPLAY 1.404255 (3700 3750);
PAINT GREEN (3700 3750);
DISPLAY INVISIBLE (3700 3750);
FORCEPROP 1 LAST COMMENT_BODY TRUE
J 0
(3330 3780);
DISPLAY 1.404255 (3330 3780);
PAINT PEACH (3330 3780);
DISPLAY INVISIBLE (3330 3780);
FORCEPROP 2 LAST PATH I9
J 0
(3575 3925);
DISPLAY 1.021277 (3575 3925);
PAINT ORANGE (3575 3925);
DISPLAY INVISIBLE (3575 3925);
FORCEADD DESIGN_NOTE..1
(-1075 1125);
PAINT PURPLE (-1075 1125);
FORCEPROP 0 LAST L3 AND VREF PIN IS NOT USED
J 0
(-1275 900);
DISPLAY 0.808511 (-1275 900);
PAINT VIOLET (-1275 900);
FORCEPROP 0 LAST L1 THE GTL2014 IS BEING USED AS LVTTL TO GTL CONVERTER, SO
J 0
(-1275 1000);
DISPLAY 0.808511 (-1275 1000);
PAINT VIOLET (-1275 1000);
FORCEPROP 0 LAST L2 THE PINS 'AX' ARE INPUTS & 'BX' OUTPUTS ARE OPEN-DRAIN
J 0
(-1275 950);
DISPLAY 0.808511 (-1275 950);
PAINT VIOLET (-1275 950);
FORCEPROP 2 LAST CDS_LIB mstr_symbols
J 0
(-1075 1125);
PAINT ORANGE (-1075 1125);
DISPLAY INVISIBLE (-1075 1125);
FORCEPROP 2 LAST BOM_COST SM_CONTROLLER
J 0
(-1275 1075);
PAINT MONO (-1275 1075);
DISPLAY INVISIBLE (-1275 1075);
FORCEPROP 1 LAST COMMENT_BODY TRUE
J 0
(-1050 1225);
DISPLAY 1.319149 (-1050 1225);
PAINT GREEN (-1050 1225);
DISPLAY INVISIBLE (-1050 1225);
FORCEPROP 2 LAST ROOM PROC_RSTS_PGOODS
J 0
(-1275 1075);
PAINT MONO (-1275 1075);
DISPLAY INVISIBLE (-1275 1075);
FORCEADD INTEL_CORP_BPAGE..1
(4400 350);
FORCEPROP 1 LAST CDS_CON_LAST_MODIFIED Fri Jun 16 17:48:39 2017
J 0
(2975 675);
PAINT ORANGE (2975 675);
DISPLAY INVISIBLE (2975 675);
FORCEPROP 1 LAST CUSTOM_TXT_CDS <CURRENT_DESIGN_SHEET> OF <TOTAL_DESIGN_SHEETS>
J 0
(3900 375);
PAINT ORANGE (3900 375);
FORCEPROP 1 LAST CUSTOM_TXT_CDS <CON_LAST_MODIFIED>
J 0
(400 450);
PAINT ORANGE (400 450);
FORCEPROP 2 LAST CUSTOM_TXT_CDS <XR_PAGE_TITLE>
J 0
(-3490 5600);
DISPLAY 0.638298 (-3490 5600);
PAINT PINK (-3490 5600);
DISPLAY INVISIBLE (-3490 5600);
FORCEPROP 1 LAST SCH_TITLE CPU SIDE BAND:RESETS & POWER GOODS
J 0
(-3550 400);
DISPLAY 1.212766 (-3550 400);
PAINT ORANGE (-3550 400);
FORCEPROP 1 LAST COMMENT_BODY TRUE
J 0
(4412 362);
DISPLAY 0.468085 (4412 362);
PAINT GREEN (4412 362);
DISPLAY INVISIBLE (4412 362);
FORCEPROP 2 LAST CDS_LIB mstr_symbols
J 0
(4400 350);
PAINT MONO (4400 350);
DISPLAY INVISIBLE (4400 350);
FORCEPROP 2 LAST PAGE_BORDER TRUE
J 0
(-3490 5600);
DISPLAY 0.638298 (-3490 5600);
PAINT PINK (-3490 5600);
DISPLAY INVISIBLE (-3490 5600);
FORCEPROP 2 LAST CDS_XR_PAGE_TITLE CR-96 : @BASEBOARD_FAB2_LIB.BASEBOARD_FAB2(SCH_1):PAGE96
J 0
(-3490 5600);
DISPLAY 0.638298 (-3490 5600);
PAINT PINK (-3490 5600);
DISPLAY INVISIBLE (-3490 5600);
FORCEADD CAD_NOTE..1
(550 2700);
FORCEPROP 0 LAST TEXT1 PLACE PU RESISTORS NEAR CPU1
J 0
(425 2550);
DISPLAY 1.255319 (425 2550);
PAINT WHITE (425 2550);
FORCEPROP 2 LAST CDS_LIB mstr_symbols
J 0
(550 2700);
PAINT ORANGE (550 2700);
DISPLAY INVISIBLE (550 2700);
FORCEPROP 1 LAST COMMENT_BODY TRUE
J 0
(575 2800);
DISPLAY 1.595745 (575 2800);
PAINT PEACH (575 2800);
DISPLAY INVISIBLE (575 2800);
FORCEADD DESIGN_NOTE..1
(-1050 3375);
PAINT PURPLE (-1050 3375);
FORCEPROP 0 LAST L3 AND VREF PIN IS NOT USED
J 0
(-1250 3150);
DISPLAY 0.808511 (-1250 3150);
PAINT VIOLET (-1250 3150);
FORCEPROP 0 LAST L2 THE PINS 'AX' ARE INPUTS & 'BX' OUTPUTS ARE OPEN-DRAIN
J 0
(-1250 3200);
DISPLAY 0.808511 (-1250 3200);
PAINT VIOLET (-1250 3200);
FORCEPROP 0 LAST L1 THE GTL2014 IS BEING USED AS LVTTL TO GTL CONVERTER, SO
J 0
(-1250 3250);
DISPLAY 0.808511 (-1250 3250);
PAINT VIOLET (-1250 3250);
FORCEPROP 2 LAST CDS_LIB mstr_symbols
J 0
(-1050 3375);
PAINT ORANGE (-1050 3375);
DISPLAY INVISIBLE (-1050 3375);
FORCEPROP 2 LAST BOM_COST SM_CONTROLLER
J 0
(-1250 3325);
PAINT MONO (-1250 3325);
DISPLAY INVISIBLE (-1250 3325);
FORCEPROP 1 LAST COMMENT_BODY TRUE
J 0
(-1025 3475);
DISPLAY 1.319149 (-1025 3475);
PAINT GREEN (-1025 3475);
DISPLAY INVISIBLE (-1025 3475);
FORCEPROP 2 LAST ROOM PROC_RSTS_PGOODS
J 0
(-1250 3325);
PAINT MONO (-1250 3325);
DISPLAY INVISIBLE (-1250 3325);
FORCEADD CAD_NOTE..1
(650 5000);
FORCEPROP 0 LAST TEXT1 PLACE PU RESISTORS NEAR CPU0
J 0
(525 4850);
DISPLAY 1.255319 (525 4850);
PAINT WHITE (525 4850);
FORCEPROP 2 LAST CDS_LIB mstr_symbols
J 0
(650 5000);
PAINT ORANGE (650 5000);
DISPLAY INVISIBLE (650 5000);
FORCEPROP 1 LAST COMMENT_BODY TRUE
J 0
(675 5100);
DISPLAY 1.595745 (675 5100);
PAINT PEACH (675 5100);
DISPLAY INVISIBLE (675 5100);
WIRE 16 -1 (1800 4600)(1800 4650);
WIRE 16 -1 (1900 4600)(1800 4600);
WIRE 16 -1 (1800 4600)(1700 4600);
WIRE 16 -1 (1700 4550)(1700 4600);
WIRE 16 -1 (1900 4550)(1900 4600);
WIRE 16 -1 (1800 2300)(1800 2375);
WIRE 16 -1 (1900 2300)(1800 2300);
WIRE 16 -1 (1800 2300)(1700 2300);
WIRE 16 -1 (1700 2250)(1700 2300);
WIRE 16 -1 (1900 2250)(1900 2300);
WIRE 16 -1 (975 2250)(975 2350);
WIRE 16 -1 (575 2250)(575 2350);
WIRE 16 -1 (975 4550)(975 4650);
WIRE 16 -1 (-325 3700)(-325 3600);
WIRE 16 -1 (-325 3750)(-325 3700);
WIRE 16 -1 (-425 3700)(-325 3700);
WIRE 16 -1 (-325 3800)(-325 3750);
WIRE 16 -1 (-425 3750)(-325 3750);
WIRE 16 -1 (-425 3800)(-325 3800);
WIRE 16 -1 (-325 1400)(-325 1300);
WIRE 16 -1 (-325 1450)(-325 1400);
WIRE 16 -1 (-425 1400)(-325 1400);
WIRE 16 -1 (-325 1500)(-325 1450);
WIRE 16 -1 (-425 1450)(-325 1450);
WIRE 16 -1 (-425 1500)(-325 1500);
WIRE 16 -1 (575 4550)(575 4650);
WIRE 16 -1 (-2100 2675)(-2100 2550);
WIRE 16 -1 (-2100 2550)(-1725 2550);
WIRE 16 -1 (-2100 2450)(-2100 2550);
WIRE 16 -1 (-1725 2550)(-1425 2550);
WIRE 16 -1 (-1725 2425)(-1725 2550);
WIRE 16 -1 (-1425 2550)(-1425 2100);
WIRE 16 -1 (-1425 2100)(-1325 2100);
WIRE 16 -1 (-2100 4850)(-2100 5000);
WIRE 16 -1 (-2100 4850)(-1650 4850);
WIRE 16 -1 (-2100 4750)(-2100 4850);
WIRE 16 -1 (-1650 4850)(-1400 4850);
WIRE 16 -1 (-1650 4750)(-1650 4850);
WIRE 16 -1 (-1400 4850)(-1400 4400);
WIRE 16 -1 (-1400 4400)(-1325 4400);
WIRE 16 -1 (-2875 2050)(-2875 2000);
WIRE 16 -1 (-2500 2050)(-2875 2050);
WIRE 16 -1 (-2775 4350)(-2775 4275);
WIRE 16 -1 (-2500 4350)(-2775 4350);
WIRE 16 -1 (-1650 4500)(-1650 4550);
WIRE 16 -1 (-1725 2225)(-1725 2175);
WIRE 16 -1 (3325 3650)(1250 3650);
FORCEPROP 2 LAST SIG_NAME PWRGD_CPU0_DRAMPWROK_ABC_G
J 0
(2550 3660);
DISPLAY 0.617021 (2550 3660);
PAINT ORANGE (2550 3660);
WIRE 16 -1 (1250 3650)(1250 4000);
WIRE 16 -1 (1250 4000)(575 4000);
WIRE 16 -1 (575 4350)(575 4000);
WIRE 16 -1 (-425 4000)(575 4000);
WIRE 16 -1 (3850 3700)(3850 3525);
WIRE 16 -1 (4150 3525)(3850 3525);
WIRE 16 -1 (4150 3700)(3850 3700);
WIRE 16 -1 (4150 3700)(4150 3525);
WIRE 16 -1 (3325 3350)(1075 3350);
FORCEPROP 2 LAST SIG_NAME PWRGD_CPU0_DRAMPWROK_DEF_G
J 0
(2550 3360);
DISPLAY 0.617021 (2550 3360);
PAINT ORANGE (2550 3360);
WIRE 16 -1 (1075 3950)(1075 3350);
WIRE 16 -1 (1075 3950)(975 3950);
WIRE 16 -1 (975 4350)(975 3950);
WIRE 16 -1 (-425 3950)(975 3950);
WIRE 16 2175 (2375 2775)(275 2775);
WIRE 16 2175 (2375 1875)(2375 2775);
WIRE 16 2175 (275 2775)(275 1875);
WIRE 16 2175 (275 1875)(2375 1875);
WIRE 16 -1 (3875 3675)(3875 3550);
WIRE 16 -1 (3875 3550)(4125 3550);
WIRE 16 -1 (4125 3675)(3875 3675);
WIRE 16 -1 (4125 3675)(4125 3550);
WIRE 16 -1 (2575 4350)(2575 4225);
WIRE 16 -1 (2575 4225)(3425 4225);
WIRE 16 -1 (3425 4350)(2575 4350);
WIRE 16 -1 (3425 4350)(3425 4225);
WIRE 16 -1 (2550 4375)(2550 4200);
WIRE 16 -1 (3450 4200)(2550 4200);
WIRE 16 -1 (3450 4375)(2550 4375);
WIRE 16 -1 (3450 4375)(3450 4200);
WIRE 16 -1 (1700 4100)(-425 4100);
WIRE 16 -1 (1700 4350)(1700 4100);
WIRE 16 -1 (3325 4100)(1700 4100);
FORCEPROP 2 LAST SIG_NAME PWRGD_CPU0_G
J 0
(2550 4110);
DISPLAY 0.617021 (2550 4110);
PAINT ORANGE (2550 4110);
WIRE 16 -1 (-425 4050)(1550 4050);
WIRE 16 -1 (1550 4050)(1550 3875);
WIRE 16 -1 (1550 3875)(1900 3875);
WIRE 16 -1 (1900 4350)(1900 3875);
WIRE 16 -1 (3325 3875)(1900 3875);
FORCEPROP 2 LAST SIG_NAME RST_CPU0_G_N
J 0
(2550 3885);
DISPLAY 0.617021 (2550 3885);
PAINT ORANGE (2550 3885);
WIRE 68 -1 (3750 3350)(3650 3350);
WIRE 68 -1 (3750 3350)(3750 3650);
WIRE 68 -1 (3750 3650)(3800 3650);
WIRE 68 -1 (3650 3900)(3750 3900);
WIRE 68 -1 (3750 3900)(3750 3650);
WIRE 16 -1 (-2300 4350)(-1325 4350);
FORCEPROP 2 LAST SIG_NAME PD_GTL2014_1_VREF
J 0
(-1885 4360);
DISPLAY 0.617021 (-1885 4360);
PAINT ORANGE (-1885 4360);
FORCEPROP 2 LASTPROP $XRERR UNIQUE?
J 0
(-2125 4360);
DISPLAY 0.638298 (-2125 4360);
PAINT MONO (-2125 4360);
DISPLAY INVISIBLE (-2125 4360);
WIRE 16 -1 (-2100 2250)(-2100 1950);
WIRE 16 -1 (-2100 1950)(-1325 1950);
FORCEPROP 2 LAST SIG_NAME PU_GTL2014_2_DIR
J 0
(-2035 1960);
DISPLAY 0.617021 (-2035 1960);
PAINT ORANGE (-2035 1960);
FORCEPROP 2 LASTPROP $XRERR UNIQUE?
J 0
(-2275 1960);
DISPLAY 0.638298 (-2275 1960);
PAINT MONO (-2275 1960);
DISPLAY INVISIBLE (-2275 1960);
WIRE 16 -1 (-2350 1450)(-2100 1450);
WIRE 16 -1 (-2350 1575)(-2350 1450);
WIRE 16 -1 (-2100 1575)(-2100 1450);
WIRE 16 -1 (-2100 1575)(-2350 1575);
WIRE 16 -1 (-2075 1425)(-2375 1425);
WIRE 16 -1 (-2375 1600)(-2375 1425);
WIRE 16 -1 (-2075 1600)(-2075 1425);
WIRE 16 -1 (-2075 1600)(-2375 1600);
WIRE 16 -1 (-2375 3900)(-2375 3725);
WIRE 16 -1 (-2075 3725)(-2375 3725);
WIRE 16 -1 (-2075 3900)(-2375 3900);
WIRE 16 -1 (-2075 3900)(-2075 3725);
WIRE 16 -1 (-2350 3875)(-2350 3750);
WIRE 16 -1 (-2350 3750)(-2100 3750);
WIRE 16 -1 (-2100 3875)(-2350 3875);
WIRE 16 -1 (-2100 3875)(-2100 3750);
WIRE 16 -1 (-2300 2050)(-1325 2050);
FORCEPROP 2 LAST SIG_NAME PD_GTL2014_2_VREF
J 0
(-2035 2060);
DISPLAY 0.617021 (-2035 2060);
PAINT ORANGE (-2035 2060);
FORCEPROP 2 LASTPROP $XRERR UNIQUE?
J 0
(-2275 2060);
DISPLAY 0.638298 (-2275 2060);
PAINT MONO (-2275 2060);
DISPLAY INVISIBLE (-2275 2060);
WIRE 16 -1 (-1325 4050)(-2150 4050);
FORCEPROP 2 LAST SIG_NAME RST_CPU0_LVC3_N
J 0
(-2085 4060);
DISPLAY 0.617021 (-2085 4060);
PAINT ORANGE (-2085 4060);
WIRE 16 -1 (-1325 1800)(-2150 1800);
FORCEPROP 2 LAST SIG_NAME PWRGD_CPU1_LVC3
J 0
(-2075 1810);
DISPLAY 0.617021 (-2075 1810);
PAINT ORANGE (-2075 1810);
WIRE 16 -1 (-1325 1750)(-2150 1750);
FORCEPROP 2 LAST SIG_NAME RST_CPU1_LVC3_N
J 0
(-2060 1760);
DISPLAY 0.617021 (-2060 1760);
PAINT ORANGE (-2060 1760);
WIRE 16 -1 (-1425 1650)(-1325 1650);
WIRE 16 -1 (-1425 1700)(-2150 1700);
FORCEPROP 2 LAST SIG_NAME PWRGD_DRAMPWRGD
J 0
(-2075 1710);
DISPLAY 0.617021 (-2075 1710);
PAINT ORANGE (-2075 1710);
WIRE 16 -1 (-1425 1700)(-1425 1650);
WIRE 16 -1 (-1325 1700)(-1425 1700);
WIRE 16 -1 (-1425 3950)(-1325 3950);
WIRE 16 -1 (-1425 4000)(-2150 4000);
FORCEPROP 2 LAST SIG_NAME PWRGD_DRAMPWRGD
J 0
(-2075 4010);
DISPLAY 0.617021 (-2075 4010);
PAINT ORANGE (-2075 4010);
WIRE 16 -1 (-1425 4000)(-1425 3950);
WIRE 16 -1 (-1325 4000)(-1425 4000);
WIRE 16 -1 (-2100 4550)(-2100 4250);
WIRE 16 -1 (-2100 4250)(-1325 4250);
FORCEPROP 2 LAST SIG_NAME PU_GTL2014_1_DIR
J 0
(-2035 4260);
DISPLAY 0.617021 (-2035 4260);
PAINT ORANGE (-2035 4260);
FORCEPROP 2 LASTPROP $XRERR UNIQUE?
J 0
(-2275 4260);
DISPLAY 0.638298 (-2275 4260);
PAINT MONO (-2275 4260);
DISPLAY INVISIBLE (-2275 4260);
WIRE 16 -1 (-1325 4100)(-2150 4100);
FORCEPROP 2 LAST SIG_NAME PWRGD_CPU0_LVC3
J 0
(-2075 4110);
DISPLAY 0.617021 (-2075 4110);
PAINT ORANGE (-2075 4110);
WIRE 16 273 (-3525 2875)(4250 2875);
WIRE 16 -1 (-425 1750)(1550 1750);
WIRE 16 -1 (1550 1750)(1550 1575);
WIRE 16 -1 (1550 1575)(1900 1575);
WIRE 16 -1 (1900 2050)(1900 1575);
WIRE 16 -1 (3325 1575)(1900 1575);
FORCEPROP 2 LAST SIG_NAME RST_CPU1_G_N
J 0
(2550 1585);
DISPLAY 0.617021 (2550 1585);
PAINT ORANGE (2550 1585);
WIRE 16 -1 (-425 1650)(975 1650);
WIRE 16 -1 (975 2050)(975 1650);
WIRE 16 -1 (1075 1650)(975 1650);
WIRE 16 -1 (1075 1650)(1075 1050);
WIRE 16 -1 (3325 1050)(1075 1050);
FORCEPROP 2 LAST SIG_NAME PWRGD_CPU1_DRAMPWROK_KLM_G
J 0
(2550 1060);
DISPLAY 0.617021 (2550 1060);
PAINT ORANGE (2550 1060);
WIRE 16 -1 (-425 1700)(575 1700);
WIRE 16 -1 (575 2050)(575 1700);
WIRE 16 -1 (1250 1700)(575 1700);
WIRE 16 -1 (1250 1350)(1250 1700);
WIRE 16 -1 (3325 1350)(1250 1350);
FORCEPROP 2 LAST SIG_NAME PWRGD_CPU1_DRAMPWROK_GHJ_G
J 0
(2550 1360);
DISPLAY 0.617021 (2550 1360);
PAINT ORANGE (2550 1360);
WIRE 16 -1 (1700 1800)(-425 1800);
WIRE 16 -1 (1700 2050)(1700 1800);
WIRE 16 -1 (3325 1800)(1700 1800);
FORCEPROP 2 LAST SIG_NAME PWRGD_CPU1_G
J 0
(2550 1810);
DISPLAY 0.617021 (2550 1810);
PAINT ORANGE (2550 1810);
WIRE 16 -1 (3800 1425)(3800 1300);
WIRE 16 -1 (3800 1300)(4050 1300);
WIRE 16 -1 (4050 1425)(3800 1425);
WIRE 16 -1 (4050 1425)(4050 1300);
WIRE 16 -1 (3775 1450)(3775 1275);
WIRE 16 -1 (4075 1275)(3775 1275);
WIRE 16 -1 (4075 1450)(3775 1450);
WIRE 16 -1 (4075 1450)(4075 1275);
WIRE 16 2175 (350 5075)(350 4200);
WIRE 16 2175 (2300 5075)(350 5075);
WIRE 16 2175 (350 4200)(2300 4200);
WIRE 16 2175 (2300 4200)(2300 5075);
DOT 1 (3750 3650);
DOT 1 (1800 2300);
DOT 1 (1700 4100);
DOT 1 (-1725 2550);
DOT 1 (-1650 4850);
DOT 1 (-325 3750);
DOT 1 (1900 1575);
DOT 1 (-2100 2550);
DOT 1 (-1425 1700);
DOT 1 (-325 1400);
DOT 1 (-325 1450);
DOT 1 (-1425 4000);
DOT 1 (-325 3700);
DOT 1 (575 1700);
DOT 1 (975 1650);
DOT 1 (1700 1800);
DOT 1 (575 4000);
DOT 1 (975 3950);
DOT 1 (1900 3875);
DOT 1 (1800 4600);
DOT 1 (-2100 4850);
FORCENOTE
CPU0
(3900 3575) 0;
DISPLAY LEFT (3900 3575);
DISPLAY 0.808511 (3900 3575);
PAINT PURPLE (3900 3575);
FORCENOTE
TO
(3900 3625) 0;
DISPLAY LEFT (3900 3625);
DISPLAY 0.808511 (3900 3625);
PAINT PURPLE (3900 3625);
FORCENOTE
CPU0/MCP JTAG DEBUG HEADER
(2600 4250) 0;
DISPLAY LEFT (2600 4250);
DISPLAY 0.808511 (2600 4250);
PAINT PURPLE (2600 4250);
FORCENOTE
TO
(2600 4300) 0;
DISPLAY LEFT (2600 4300);
DISPLAY 0.808511 (2600 4300);
PAINT PURPLE (2600 4300);
FORCENOTE
TO
(3900 1375) 0;
DISPLAY LEFT (3900 1375);
DISPLAY 1.021277 (3900 1375);
PAINT PURPLE (3900 1375);
FORCENOTE
CPU1
(3850 1325) 0;
DISPLAY LEFT (3850 1325);
DISPLAY 1.021277 (3850 1325);
PAINT PURPLE (3850 1325);
FORCENOTE
FROM
(-2300 3825) 0;
DISPLAY LEFT (-2300 3825);
DISPLAY 0.808511 (-2300 3825);
PAINT PURPLE (-2300 3825);
FORCENOTE
CPLD
(-2300 3775) 0;
DISPLAY LEFT (-2300 3775);
DISPLAY 0.808511 (-2300 3775);
PAINT PURPLE (-2300 3775);
FORCENOTE
FROM
(-2300 1525) 0;
DISPLAY LEFT (-2300 1525);
DISPLAY 1.021277 (-2300 1525);
PAINT PURPLE (-2300 1525);
FORCENOTE
CPLD
(-2300 1475) 0;
DISPLAY LEFT (-2300 1475);
DISPLAY 1.021277 (-2300 1475);
PAINT PURPLE (-2300 1475);
FORCENOTE
BOM_COST=PROC_SIDEBAND
(-3375 600) 0;
DISPLAY LEFT (-3375 600);
DISPLAY 1.276596 (-3375 600);
PAINT PURPLE (-3375 600);
FORCENOTE
ROOM=PROC_RSTS_PGOODS
(-3375 675) 0;
DISPLAY LEFT (-3375 675);
DISPLAY 1.276596 (-3375 675);
PAINT PURPLE (-3375 675);
QUIT
